G04 ================== begin FILE IDENTIFICATION RECORD ==================*
G04 Layout Name:  9052_F0T_PDB_Converter_Brick_F_V03_1208_1600.brd*
G04 Film Name:    vcc*
G04 File Format:  Gerber RS274X*
G04 File Origin:  Cadence Allegro 17.2-S081*
G04 Origin Date:  Wed Dec 21 09:54:58 2022*
G04 *
G04 Layer:  DRAWING FORMAT/TITLE_BLOCK_A*
G04 Layer:  PIN/SPECIAL_DRILL*
G04 Layer:  DRAWING FORMAT/TITLE_BLOCK*
G04 Layer:  VIA CLASS/VCC*
G04 Layer:  PIN/VCC*
G04 Layer:  MANUFACTURING/PHOTOPLOT_OUTLINE*
G04 Layer:  ETCH/VCC*
G04 Layer:  DRAWING FORMAT/TITLE_DATA_VCC*
G04 *
G04 Offset:    (0.00 0.00)*
G04 Mirror:    No*
G04 Mode:      Negative*
G04 Rotation:  0*
G04 FullContactRelief:  No*
G04 UndefLineWidth:     6.00*
G04 ================== end FILE IDENTIFICATION RECORD ====================*
%FSLAX25Y25*MOIN*%
%IR0*IPPOS*OFA0.00000B0.00000*MIA0B0*SFA1.00000B1.00000*%
%ADD38C,.02*%
%ADD10C,.03*%
%AMMACRO42*
4,1,41,-.40714,-.11826,
-.427771,-.11755,
-.447965,-.113268,
-.467108,-.105544,
-.48462,-.094614,
-.499967,-.080809,
-.512684,-.064548,
-.522385,-.046326,
-.528773,-.026697,
-.531656,-.006256,
-.530946,.014374,
-.526664,.034568,
-.518941,.053712,
-.50801,.071223,
-.494205,.086571,
-.477944,.099288,
-.459723,.108988,
-.440093,.115377,
-.419653,.11826,
-.40714,.11826,
.33517,.07906,
.45275,.07906,
.466479,.077859,
.47979,.074292,
.49228,.068468,
.503569,.060563,
.513313,.050819,
.521218,.03953,
.527042,.02704,
.530609,.013729,
.53181,0.0,
.530609,-.013729,
.527042,-.02704,
.521218,-.03953,
.513313,-.050819,
.503569,-.060563,
.49228,-.068468,
.47979,-.074292,
.466479,-.077859,
.45275,-.07906,
.33517,-.07906,
-.40714,-.11826,
0.0*
%
%ADD42MACRO42*%
%AMMACRO12*
4,1,41,.45275,-.05906,
.463006,-.058163,
.47295,-.055498,
.48228,-.051147,
.490713,-.045243,
.497993,-.037963,
.503897,-.02953,
.508248,-.0202,
.510913,-.010256,
.51181,0.0,
.510913,.010256,
.508248,.0202,
.503897,.02953,
.497993,.037963,
.490713,.045243,
.48228,.051147,
.47295,.055498,
.463006,.058163,
.45275,.05906,
.33464,.05906,
-.4082,.09829,
-.425347,.097699,
-.442131,.09414,
-.458041,.08772,
-.472595,.078635,
-.485351,.06716,
-.49592,.053645,
-.503981,.0385,
-.509291,.022185,
-.511686,.005196,
-.511095,-.011951,
-.507536,-.028734,
-.501116,-.044645,
-.492031,-.059199,
-.480557,-.071954,
-.467041,-.082523,
-.451896,-.090585,
-.435582,-.095894,
-.418593,-.09829,
-.4082,-.09829,
.33464,-.05906,
.45275,-.05906,
0.0*
%
%ADD12MACRO12*%
%ADD31C,.06*%
%ADD26C,.062*%
%ADD16C,.054*%
%AMMACRO27*
4,1,36,.0025,0.0,
.002462,.000434,
.002349,.000855,
.002165,.00125,
.001915,.001607,
.001607,.001915,
.00125,.002165,
.000855,.002349,
.000434,.002462,
0.0,.0025,
-.000434,.002462,
-.000855,.002349,
-.00125,.002165,
-.001607,.001915,
-.001915,.001607,
-.002165,.00125,
-.002349,.000855,
-.002462,.000434,
-.0025,0.0,
-.002462,-.000434,
-.002349,-.000855,
-.002165,-.00125,
-.001915,-.001607,
-.001607,-.001915,
-.00125,-.002165,
-.000855,-.002349,
-.000434,-.002462,
0.0,-.0025,
.000434,-.002462,
.000855,-.002349,
.00125,-.002165,
.001607,-.001915,
.001915,-.001607,
.002165,-.00125,
.002349,-.000855,
.002462,-.000434,
.0025,0.0,
270.*
%
%ADD27MACRO27*%
%AMMACRO20*
4,1,36,.0025,0.0,
.002462,.000434,
.002349,.000855,
.002165,.00125,
.001915,.001607,
.001607,.001915,
.00125,.002165,
.000855,.002349,
.000434,.002462,
0.0,.0025,
-.000434,.002462,
-.000855,.002349,
-.00125,.002165,
-.001607,.001915,
-.001915,.001607,
-.002165,.00125,
-.002349,.000855,
-.002462,.000434,
-.0025,0.0,
-.002462,-.000434,
-.002349,-.000855,
-.002165,-.00125,
-.001915,-.001607,
-.001607,-.001915,
-.00125,-.002165,
-.000855,-.002349,
-.000434,-.002462,
0.0,-.0025,
.000434,-.002462,
.000855,-.002349,
.00125,-.002165,
.001607,-.001915,
.001915,-.001607,
.002165,-.00125,
.002349,-.000855,
.002462,-.000434,
.0025,0.0,
180.*
%
%ADD20MACRO20*%
%ADD29C,.083*%
%ADD28C,.056*%
%ADD43C,.066*%
%ADD35C,.06015*%
%ADD40C,.087*%
%AMMACRO36*
4,1,36,0.0,.019,
-.003299,.018711,
-.006498,.017854,
-.0095,.016454,
-.012213,.014555,
-.014555,.012213,
-.016454,.0095,
-.017854,.006498,
-.018711,.003299,
-.019,0.0,
-.018711,-.003299,
-.017854,-.006498,
-.016454,-.0095,
-.014555,-.012213,
-.012213,-.014555,
-.0095,-.016454,
-.006498,-.017854,
-.003299,-.018711,
0.0,-.019,
.003299,-.018711,
.006498,-.017854,
.0095,-.016454,
.012213,-.014555,
.014555,-.012213,
.016454,-.0095,
.017854,-.006498,
.018711,-.003299,
.019,0.0,
.018711,.003299,
.017854,.006498,
.016454,.0095,
.014555,.012213,
.012213,.014555,
.0095,.016454,
.006498,.017854,
.003299,.018711,
0.0,.019,
0.0*
%
%ADD36MACRO36*%
%AMMACRO33*
4,1,16,.04271,.02503,
.046408,.017233,
.048695,.008913,
.049503,.000322,
.048807,-.008279,
.046628,-.016629,
.043032,-.024473,
.04271,-.02503,
.0478,-.03012,
.052304,-.021362,
.055219,-.011955,
.056456,-.002185,
.055978,.007652,
.053799,.017256,
.049985,.026336,
.0478,.03012,
.04271,.02503,
270.*
4,1,16,.02503,-.04271,
.017233,-.046408,
.008913,-.048695,
.000322,-.049503,
-.008279,-.048807,
-.016629,-.046628,
-.024473,-.043032,
-.02503,-.04271,
-.03012,-.0478,
-.021362,-.052304,
-.011955,-.055219,
-.002185,-.056456,
.007652,-.055978,
.017256,-.053799,
.026336,-.049985,
.03012,-.0478,
.02503,-.04271,
270.*
4,1,16,-.04271,-.02503,
-.046408,-.017233,
-.048695,-.008913,
-.049503,-.000322,
-.048807,.008279,
-.046628,.016629,
-.043032,.024473,
-.04271,.02503,
-.0478,.03012,
-.052304,.021362,
-.055219,.011955,
-.056456,.002185,
-.055978,-.007652,
-.053799,-.017256,
-.049985,-.026336,
-.0478,-.03012,
-.04271,-.02503,
270.*
4,1,16,-.02503,.04271,
-.017233,.046408,
-.008913,.048695,
-.000322,.049503,
.008279,.048807,
.016629,.046628,
.024473,.043032,
.02503,.04271,
.03012,.0478,
.021362,.052304,
.011955,.055219,
.002185,.056456,
-.007652,.055978,
-.017256,.053799,
-.026336,.049985,
-.03012,.0478,
-.02503,.04271,
270.*
%
%ADD33MACRO33*%
%AMMACRO44*
4,1,16,.02657,.01597,
.02894,.011114,
.03043,.005919,
.030995,.000545,
.030619,-.004845,
.029313,-.010088,
.027115,-.015025,
.02657,-.01597,
.03164,-.02104,
.034813,-.015226,
.036928,-.00895,
.037921,-.002401,
.037762,.00422,
.036455,.010713,
.034041,.016881,
.03164,.02104,
.02657,.01597,
90.*
4,1,16,.01597,-.02657,
.011114,-.02894,
.005919,-.03043,
.000545,-.030995,
-.004845,-.030619,
-.010088,-.029313,
-.015025,-.027115,
-.01597,-.02657,
-.02104,-.03164,
-.015226,-.034813,
-.00895,-.036928,
-.002401,-.037921,
.00422,-.037762,
.010713,-.036455,
.016881,-.034041,
.02104,-.03164,
.01597,-.02657,
90.*
4,1,16,-.02657,-.01597,
-.02894,-.011114,
-.03043,-.005919,
-.030995,-.000545,
-.030619,.004845,
-.029313,.010088,
-.027115,.015025,
-.02657,.01597,
-.03164,.02104,
-.034813,.015226,
-.036928,.00895,
-.037921,.002401,
-.037762,-.00422,
-.036455,-.010713,
-.034041,-.016881,
-.03164,-.02104,
-.02657,-.01597,
90.*
4,1,16,-.01597,.02657,
-.011114,.02894,
-.005919,.03043,
-.000545,.030995,
.004845,.030619,
.010088,.029313,
.015025,.027115,
.01597,.02657,
.02104,.03164,
.015226,.034813,
.00895,.036928,
.002401,.037921,
-.00422,.037762,
-.010713,.036455,
-.016881,.034041,
-.02104,.03164,
-.01597,.02657,
90.*
%
%ADD44MACRO44*%
%AMMACRO25*
4,1,16,.02511,.01451,
.027248,.009929,
.028558,.005047,
.029001,.000011,
.028562,-.005025,
.027256,-.009909,
.025121,-.014491,
.02511,-.01451,
.0302,-.01959,
.033143,-.014048,
.035079,-.00808,
.035949,-.001865,
.035727,.004405,
.034419,.010542,
.032065,.016359,
.0302,.01959,
.02511,.01451,
0.0*
4,1,16,.01451,-.02511,
.009929,-.027248,
.005047,-.028558,
.000011,-.029001,
-.005025,-.028562,
-.009909,-.027256,
-.014491,-.025121,
-.01451,-.02511,
-.01959,-.0302,
-.014048,-.033143,
-.00808,-.035079,
-.001865,-.035949,
.004405,-.035727,
.010542,-.034419,
.016359,-.032065,
.01959,-.0302,
.01451,-.02511,
0.0*
4,1,16,-.02511,-.01451,
-.027248,-.009929,
-.028558,-.005047,
-.029001,-.000011,
-.028562,.005025,
-.027256,.009909,
-.025121,.014491,
-.02511,.01451,
-.0302,.01959,
-.033143,.014048,
-.035079,.00808,
-.035949,.001865,
-.035727,-.004405,
-.034419,-.010542,
-.032065,-.016359,
-.0302,-.01959,
-.02511,-.01451,
0.0*
4,1,16,-.01451,.02511,
-.009929,.027248,
-.005047,.028558,
-.000011,.029001,
.005025,.028562,
.009909,.027256,
.014491,.025121,
.01451,.02511,
.01959,.0302,
.014048,.033143,
.00808,.035079,
.001865,.035949,
-.004405,.035727,
-.010542,.034419,
-.016359,.032065,
-.01959,.0302,
-.01451,.02511,
0.0*
%
%ADD25MACRO25*%
%AMMACRO46*
4,1,15,.03682,.01914,
.039584,.012455,
.041146,.005393,
.041457,-.001834,
.040509,-.009005,
.03833,-.015903,
.03682,-.01914,
.04197,-.0243,
.045552,-.016643,
.04775,-.00848,
.048497,-.000059,
.047771,.008363,
.045593,.016531,
.042029,.024197,
.04197,.0243,
.03682,.01914,
90.*
4,1,15,.01914,-.03682,
.012455,-.039584,
.005393,-.041146,
-.001834,-.041457,
-.009005,-.040509,
-.015903,-.03833,
-.01914,-.03682,
-.0243,-.04197,
-.016643,-.045552,
-.00848,-.04775,
-.000059,-.048497,
.008363,-.047771,
.016531,-.045593,
.024197,-.042029,
.0243,-.04197,
.01914,-.03682,
90.*
4,1,15,-.03682,-.01914,
-.039584,-.012455,
-.041146,-.005393,
-.041457,.001834,
-.040509,.009005,
-.03833,.015903,
-.03682,.01914,
-.04197,.0243,
-.045552,.016643,
-.04775,.00848,
-.048497,.000059,
-.047771,-.008363,
-.045593,-.016531,
-.042029,-.024197,
-.04197,-.0243,
-.03682,-.01914,
90.*
4,1,15,-.01914,.03682,
-.012455,.039584,
-.005393,.041146,
.001834,.041457,
.009005,.040509,
.015903,.03833,
.01914,.03682,
.0243,.04197,
.016643,.045552,
.00848,.04775,
.000059,.048497,
-.008363,.047771,
-.016531,.045593,
-.024197,.042029,
-.0243,.04197,
-.01914,.03682,
90.*
%
%ADD46MACRO46*%
%AMMACRO45*
4,1,15,-.03682,.01914,
-.039584,.012455,
-.041146,.005393,
-.041457,-.001834,
-.040509,-.009005,
-.03833,-.015903,
-.03682,-.01914,
-.04197,-.0243,
-.045552,-.016643,
-.04775,-.00848,
-.048497,-.000059,
-.047771,.008363,
-.045593,.016531,
-.042029,.024197,
-.04197,.0243,
-.03682,.01914,
90.*
4,1,15,-.01914,-.03682,
-.012455,-.039584,
-.005393,-.041146,
.001834,-.041457,
.009005,-.040509,
.015903,-.03833,
.01914,-.03682,
.0243,-.04197,
.016643,-.045552,
.00848,-.04775,
.000059,-.048497,
-.008363,-.047771,
-.016531,-.045593,
-.024197,-.042029,
-.0243,-.04197,
-.01914,-.03682,
90.*
4,1,15,.03682,-.01914,
.039584,-.012455,
.041146,-.005393,
.041457,.001834,
.040509,.009005,
.03833,.015903,
.03682,.01914,
.04197,.0243,
.045552,.016643,
.04775,.00848,
.048497,.000059,
.047771,-.008363,
.045593,-.016531,
.042029,-.024197,
.04197,-.0243,
.03682,-.01914,
90.*
4,1,15,.01914,.03682,
.012455,.039584,
.005393,.041146,
-.001834,.041457,
-.009005,.040509,
-.015903,.03833,
-.01914,.03682,
-.0243,.04197,
-.016643,.045552,
-.00848,.04775,
-.000059,.048497,
.008363,.047771,
.016531,.045593,
.024197,.042029,
.0243,.04197,
.01914,.03682,
90.*
%
%ADD45MACRO45*%
%ADD24C,.103*%
%AMMACRO13*
4,1,36,0.0,.005,
.000868,.004924,
.00171,.004698,
.0025,.00433,
.003214,.00383,
.00383,.003214,
.00433,.0025,
.004698,.00171,
.004924,.000868,
.005,0.0,
.004924,-.000868,
.004698,-.00171,
.00433,-.0025,
.00383,-.003214,
.003214,-.00383,
.0025,-.00433,
.00171,-.004698,
.000868,-.004924,
0.0,-.005,
-.000868,-.004924,
-.00171,-.004698,
-.0025,-.00433,
-.003214,-.00383,
-.00383,-.003214,
-.00433,-.0025,
-.004698,-.00171,
-.004924,-.000868,
-.005,0.0,
-.004924,.000868,
-.004698,.00171,
-.00433,.0025,
-.00383,.003214,
-.003214,.00383,
-.0025,.00433,
-.00171,.004698,
-.000868,.004924,
0.0,.005,
270.*
%
%ADD13MACRO13*%
%ADD11C,.125*%
%ADD14C,.117*%
%ADD22C,.155*%
%ADD19C,.237*%
%ADD30C,.256*%
%AMMACRO23*
4,1,36,.0025,0.0,
.002462,.000434,
.002349,.000855,
.002165,.00125,
.001915,.001607,
.001607,.001915,
.00125,.002165,
.000855,.002349,
.000434,.002462,
0.0,.0025,
-.000434,.002462,
-.000855,.002349,
-.00125,.002165,
-.001607,.001915,
-.001915,.001607,
-.002165,.00125,
-.002349,.000855,
-.002462,.000434,
-.0025,0.0,
-.002462,-.000434,
-.002349,-.000855,
-.002165,-.00125,
-.001915,-.001607,
-.001607,-.001915,
-.00125,-.002165,
-.000855,-.002349,
-.000434,-.002462,
0.0,-.0025,
.000434,-.002462,
.000855,-.002349,
.00125,-.002165,
.001607,-.001915,
.001915,-.001607,
.002165,-.00125,
.002349,-.000855,
.002462,-.000434,
.0025,0.0,
90.*
%
%ADD23MACRO23*%
%ADD18C,.186*%
%ADD48C,.187*%
%AMMACRO37*
4,1,36,0.0,.019,
-.003299,.018711,
-.006498,.017854,
-.0095,.016454,
-.012213,.014555,
-.014555,.012213,
-.016454,.0095,
-.017854,.006498,
-.018711,.003299,
-.019,0.0,
-.018711,-.003299,
-.017854,-.006498,
-.016454,-.0095,
-.014555,-.012213,
-.012213,-.014555,
-.0095,-.016454,
-.006498,-.017854,
-.003299,-.018711,
0.0,-.019,
.003299,-.018711,
.006498,-.017854,
.0095,-.016454,
.012213,-.014555,
.014555,-.012213,
.016454,-.0095,
.017854,-.006498,
.018711,-.003299,
.019,0.0,
.018711,.003299,
.017854,.006498,
.016454,.0095,
.014555,.012213,
.012213,.014555,
.0095,.016454,
.006498,.017854,
.003299,.018711,
0.0,.019,
270.*
%
%ADD37MACRO37*%
%AMMACRO21*
4,1,36,.0025,0.0,
.002462,.000434,
.002349,.000855,
.002165,.00125,
.001915,.001607,
.001607,.001915,
.00125,.002165,
.000855,.002349,
.000434,.002462,
0.0,.0025,
-.000434,.002462,
-.000855,.002349,
-.00125,.002165,
-.001607,.001915,
-.001915,.001607,
-.002165,.00125,
-.002349,.000855,
-.002462,.000434,
-.0025,0.0,
-.002462,-.000434,
-.002349,-.000855,
-.002165,-.00125,
-.001915,-.001607,
-.001607,-.001915,
-.00125,-.002165,
-.000855,-.002349,
-.000434,-.002462,
0.0,-.0025,
.000434,-.002462,
.000855,-.002349,
.00125,-.002165,
.001607,-.001915,
.001915,-.001607,
.002165,-.00125,
.002349,-.000855,
.002462,-.000434,
.0025,0.0,
0.0*
%
%ADD21MACRO21*%
%AMMACRO17*
4,1,15,.02217,.01156,
.023841,.007535,
.024787,.00328,
.02498,-.001074,
.024414,-.005395,
.023106,-.009553,
.02217,-.01156,
.0273,-.01669,
.029783,-.011696,
.031362,-.006346,
.031987,-.000804,
.031641,.004763,
.030333,.010185,
.028104,.015297,
.0273,.01669,
.02217,.01156,
270.*
4,1,15,.01156,-.02217,
.007535,-.023841,
.00328,-.024787,
-.001074,-.02498,
-.005395,-.024414,
-.009553,-.023106,
-.01156,-.02217,
-.01669,-.0273,
-.011696,-.029783,
-.006346,-.031362,
-.000804,-.031987,
.004763,-.031641,
.010185,-.030333,
.015297,-.028104,
.01669,-.0273,
.01156,-.02217,
270.*
4,1,15,-.02217,-.01156,
-.023841,-.007535,
-.024787,-.00328,
-.02498,.001074,
-.024414,.005395,
-.023106,.009553,
-.02217,.01156,
-.0273,.01669,
-.029783,.011696,
-.031362,.006346,
-.031987,.000804,
-.031641,-.004763,
-.030333,-.010185,
-.028104,-.015297,
-.0273,-.01669,
-.02217,-.01156,
270.*
4,1,15,-.01156,.02217,
-.007535,.023841,
-.00328,.024787,
.001074,.02498,
.005395,.024414,
.009553,.023106,
.01156,.02217,
.01669,.0273,
.011696,.029783,
.006346,.031362,
.000804,.031987,
-.004763,.031641,
-.010185,.030333,
-.015297,.028104,
-.01669,.0273,
-.01156,.02217,
270.*
%
%ADD17MACRO17*%
%AMMACRO32*
4,1,15,.02438,.01377,
.026401,.009327,
.027619,.004601,
.027999,-.000265,
.027527,-.005123,
.02622,-.009825,
.02438,-.01377,
.02948,-.01887,
.032309,-.013464,
.034156,-.007649,
.034965,-.001602,
.034712,.004494,
.033405,.010454,
.031082,.016095,
.02948,.01887,
.02438,.01377,
270.*
4,1,15,.01377,-.02438,
.009327,-.026401,
.004601,-.027619,
-.000265,-.027999,
-.005123,-.027527,
-.009825,-.02622,
-.01377,-.02438,
-.01887,-.02948,
-.013464,-.032309,
-.007649,-.034156,
-.001602,-.034965,
.004494,-.034712,
.010454,-.033405,
.016095,-.031082,
.01887,-.02948,
.01377,-.02438,
270.*
4,1,15,-.02438,-.01377,
-.026401,-.009327,
-.027619,-.004601,
-.027999,.000265,
-.027527,.005123,
-.02622,.009825,
-.02438,.01377,
-.02948,.01887,
-.032309,.013464,
-.034156,.007649,
-.034965,.001602,
-.034712,-.004494,
-.033405,-.010454,
-.031082,-.016095,
-.02948,-.01887,
-.02438,-.01377,
270.*
4,1,15,-.01377,.02438,
-.009327,.026401,
-.004601,.027619,
.000265,.027999,
.005123,.027527,
.009825,.02622,
.01377,.02438,
.01887,.02948,
.013464,.032309,
.007649,.034156,
.001602,.034965,
-.004494,.034712,
-.010454,.033405,
-.016095,.031082,
-.01887,.02948,
-.01377,.02438,
270.*
%
%ADD32MACRO32*%
%AMMACRO15*
4,1,15,.02475,.01414,
.026829,.009627,
.028094,.004822,
.028504,-.000129,
.028049,-.005077,
.026741,-.009871,
.02475,-.01414,
.02984,-.01923,
.032726,-.013756,
.034617,-.007864,
.035457,-.001734,
.03522,.00445,
.033912,.010498,
.031574,.016227,
.02984,.01923,
.02475,.01414,
270.*
4,1,15,.01414,-.02475,
.009627,-.026829,
.004822,-.028094,
-.000129,-.028504,
-.005077,-.028049,
-.009871,-.026741,
-.01414,-.02475,
-.01923,-.02984,
-.013756,-.032726,
-.007864,-.034617,
-.001734,-.035457,
.00445,-.03522,
.010498,-.033912,
.016227,-.031574,
.01923,-.02984,
.01414,-.02475,
270.*
4,1,15,-.02475,-.01414,
-.026829,-.009627,
-.028094,-.004822,
-.028504,.000129,
-.028049,.005077,
-.026741,.009871,
-.02475,.01414,
-.02984,.01923,
-.032726,.013756,
-.034617,.007864,
-.035457,.001734,
-.03522,-.00445,
-.033912,-.010498,
-.031574,-.016227,
-.02984,-.01923,
-.02475,-.01414,
270.*
4,1,15,-.01414,.02475,
-.009627,.026829,
-.004822,.028094,
.000129,.028504,
.005077,.028049,
.009871,.026741,
.01414,.02475,
.01923,.02984,
.013756,.032726,
.007864,.034617,
.001734,.035457,
-.00445,.03522,
-.010498,.033912,
-.016227,.031574,
-.01923,.02984,
-.01414,.02475,
270.*
%
%ADD15MACRO15*%
%AMMACRO47*
4,1,18,.10783,.07955,
.120006,.059617,
.128535,.037873,
.133159,.014977,
.133736,-.008373,
.130251,-.031469,
.122807,-.053609,
.111633,-.074119,
.10783,-.07955,
.11284,-.08455,
.125808,-.063671,
.134953,-.040857,
.139997,-.016802,
.140788,.007763,
.137301,.032093,
.129642,.055447,
.118045,.077117,
.11284,.08455,
.10783,.07955,
270.*
4,1,18,.07955,-.10783,
.059617,-.120006,
.037873,-.128535,
.014977,-.133159,
-.008373,-.133736,
-.031469,-.130251,
-.053609,-.122807,
-.074119,-.111633,
-.07955,-.10783,
-.08455,-.11284,
-.063671,-.125808,
-.040857,-.134953,
-.016802,-.139997,
.007763,-.140788,
.032093,-.137301,
.055447,-.129642,
.077117,-.118045,
.08455,-.11284,
.07955,-.10783,
270.*
4,1,18,-.10783,-.07955,
-.120006,-.059617,
-.128535,-.037873,
-.133159,-.014977,
-.133736,.008373,
-.130251,.031469,
-.122807,.053609,
-.111633,.074119,
-.10783,.07955,
-.11284,.08455,
-.125808,.063671,
-.134953,.040857,
-.139997,.016802,
-.140788,-.007763,
-.137301,-.032093,
-.129642,-.055447,
-.118045,-.077117,
-.11284,-.08455,
-.10783,-.07955,
270.*
4,1,18,-.07955,.10783,
-.059617,.120006,
-.037873,.128535,
-.014977,.133159,
.008373,.133736,
.031469,.130251,
.053609,.122807,
.074119,.111633,
.07955,.10783,
.08455,.11284,
.063671,.125808,
.040857,.134953,
.016802,.139997,
-.007763,.140788,
-.032093,.137301,
-.055447,.129642,
-.077117,.118045,
-.08455,.11284,
-.07955,.10783,
270.*
%
%ADD47MACRO47*%
%AMMACRO39*
4,1,15,.03682,.01914,
.039584,.012455,
.041146,.005393,
.041457,-.001834,
.040509,-.009005,
.03833,-.015903,
.03682,-.01914,
.04197,-.0243,
.045552,-.016643,
.04775,-.00848,
.048497,-.000059,
.047771,.008363,
.045593,.016531,
.042029,.024197,
.04197,.0243,
.03682,.01914,
270.*
4,1,15,.01914,-.03682,
.012455,-.039584,
.005393,-.041146,
-.001834,-.041457,
-.009005,-.040509,
-.015903,-.03833,
-.01914,-.03682,
-.0243,-.04197,
-.016643,-.045552,
-.00848,-.04775,
-.000059,-.048497,
.008363,-.047771,
.016531,-.045593,
.024197,-.042029,
.0243,-.04197,
.01914,-.03682,
270.*
4,1,15,-.03682,-.01914,
-.039584,-.012455,
-.041146,-.005393,
-.041457,.001834,
-.040509,.009005,
-.03833,.015903,
-.03682,.01914,
-.04197,.0243,
-.045552,.016643,
-.04775,.00848,
-.048497,.000059,
-.047771,-.008363,
-.045593,-.016531,
-.042029,-.024197,
-.04197,-.0243,
-.03682,-.01914,
270.*
4,1,15,-.01914,.03682,
-.012455,.039584,
-.005393,.041146,
.001834,.041457,
.009005,.040509,
.015903,.03833,
.01914,.03682,
.0243,.04197,
.016643,.045552,
.00848,.04775,
.000059,.048497,
-.008363,.047771,
-.016531,.045593,
-.024197,.042029,
-.0243,.04197,
-.01914,.03682,
270.*
%
%ADD39MACRO39*%
%AMMACRO34*
4,1,17,.03273,.02212,
.036074,.0161,
.038322,.009592,
.039405,.002791,
.039291,-.004094,
.037983,-.010854,
.035521,-.017285,
.03273,-.02212,
.03775,-.02715,
.041891,-.020182,
.044759,-.012601,
.046267,-.004638,
.04637,.003467,
.045063,.011466,
.042388,.019117,
.038424,.026188,
.03775,.02715,
.03273,.02212,
270.*
4,1,17,.02212,-.03273,
.0161,-.036074,
.009592,-.038322,
.002791,-.039405,
-.004094,-.039291,
-.010854,-.037983,
-.017285,-.035521,
-.02212,-.03273,
-.02715,-.03775,
-.020182,-.041891,
-.012601,-.044759,
-.004638,-.046267,
.003467,-.04637,
.011466,-.045063,
.019117,-.042388,
.026188,-.038424,
.02715,-.03775,
.02212,-.03273,
270.*
4,1,17,-.03273,-.02212,
-.036074,-.0161,
-.038322,-.009592,
-.039405,-.002791,
-.039291,.004094,
-.037983,.010854,
-.035521,.017285,
-.03273,.02212,
-.03775,.02715,
-.041891,.020182,
-.044759,.012601,
-.046267,.004638,
-.04637,-.003467,
-.045063,-.011466,
-.042388,-.019117,
-.038424,-.026188,
-.03775,-.02715,
-.03273,-.02212,
270.*
4,1,17,-.02212,.03273,
-.0161,.036074,
-.009592,.038322,
-.002791,.039405,
.004094,.039291,
.010854,.037983,
.017285,.035521,
.02212,.03273,
.02715,.03775,
.020182,.041891,
.012601,.044759,
.004638,.046267,
-.003467,.04637,
-.011466,.045063,
-.019117,.042388,
-.026188,.038424,
-.02715,.03775,
-.02212,.03273,
270.*
%
%ADD34MACRO34*%
%AMMACRO41*
4,1,15,-.03682,.01914,
-.039584,.012455,
-.041146,.005393,
-.041457,-.001834,
-.040509,-.009005,
-.03833,-.015903,
-.03682,-.01914,
-.04197,-.0243,
-.045552,-.016643,
-.04775,-.00848,
-.048497,-.000059,
-.047771,.008363,
-.045593,.016531,
-.042029,.024197,
-.04197,.0243,
-.03682,.01914,
270.*
4,1,15,-.01914,-.03682,
-.012455,-.039584,
-.005393,-.041146,
.001834,-.041457,
.009005,-.040509,
.015903,-.03833,
.01914,-.03682,
.0243,-.04197,
.016643,-.045552,
.00848,-.04775,
.000059,-.048497,
-.008363,-.047771,
-.016531,-.045593,
-.024197,-.042029,
-.0243,-.04197,
-.01914,-.03682,
270.*
4,1,15,.03682,-.01914,
.039584,-.012455,
.041146,-.005393,
.041457,.001834,
.040509,.009005,
.03833,.015903,
.03682,.01914,
.04197,.0243,
.045552,.016643,
.04775,.00848,
.048497,.000059,
.047771,-.008363,
.045593,-.016531,
.042029,-.024197,
.04197,-.0243,
.03682,-.01914,
270.*
4,1,15,.01914,.03682,
.012455,.039584,
.005393,.041146,
-.001834,.041457,
-.009005,.040509,
-.015903,.03833,
-.01914,.03682,
-.0243,.04197,
-.016643,.045552,
-.00848,.04775,
-.000059,.048497,
.008363,.047771,
.016531,.045593,
.024197,.042029,
.0243,.04197,
.01914,.03682,
270.*
%
%ADD41MACRO41*%
%ADD49C,.018*%
%ADD50C,.006*%
%ADD57C,.07006*%
%ADD61C,.11022*%
%ADD54C,.10006*%
%ADD56C,.11006*%
%ADD59C,.11206*%
%ADD51C,.12707*%
%ADD52C,.16506*%
%ADD60C,.28606*%
%ADD53C,.19606*%
%ADD55C,.32598*%
%ADD58C,.18498*%
G75*
%LPD*%
G75*
G36*
G01X-297025Y-1013390D02*
X3691357D01*
Y1828909D01*
X-297025D01*
Y-1013390D01*
G37*
%LPC*%
G75*
G36*
G01X141706Y574740D02*
X149085D01*
G02X149227Y574681I0J-200D01*
G01X153441Y570467D01*
G02X153500Y570325I-141J-142D01*
G01Y475411D01*
G02X153441Y475269I-200J0D01*
G01X148412Y470240D01*
G02X148270Y470181I-142J141D01*
G01X94082D01*
G02X93897Y470306I0J200D01*
G01X93734Y470706D01*
X93759Y470825D01*
X93804Y470868D01*
G03X98598Y482205I-11008J11337D01*
G03X82795Y498008I-15803J0D01*
G03X68500Y488942I0J-15803D01*
G01X68479Y488896D01*
X68400Y488837D01*
X67972Y488772D01*
X67879Y488804D01*
X67844Y488842D01*
G03Y475568I-7214J-6637D01*
G01X67879Y475606D01*
X67972Y475638D01*
X68400Y475573D01*
X68479Y475514D01*
X68500Y475468D01*
G03X71786Y470868I14294J6738D01*
G01X71831Y470825D01*
X71856Y470706D01*
X71693Y470306D01*
G02X71508Y470181I-185J75D01*
G01X63966D01*
G03X62552Y469595I0J-1999D01*
G01X58586Y465629D01*
G03X58000Y464215I1413J-1414D01*
G01Y309100D01*
G02X57800Y308900I-200J0D01*
G01X35100D01*
G03X33686Y308314I0J-1999D01*
G01X30686Y305314D01*
G03X30100Y303900I1413J-1414D01*
G01Y269900D01*
G03X30686Y268486I1999J0D01*
G01X34486Y264686D01*
G03X35900Y264100I1414J1413D01*
G01X105337D01*
G02X105513Y263995I0J-200D01*
G01X105706Y263637D01*
X105701Y263527D01*
X105671Y263481D01*
G03X105098Y261560I2929J-1920D01*
G03X105398Y260141I3502J-1D01*
G02Y259979I-183J-81D01*
G03X105098Y258560I3202J-1418D01*
G03X105398Y257141I3502J-1D01*
G02Y256979I-183J-81D01*
G03X105098Y255560I3202J-1418D01*
G03X108600Y252058I3502J0D01*
G03X110019Y252358I1J3502D01*
G02X110181I81J-183D01*
G03X111600Y252058I1418J3202D01*
G03X115102Y255560I0J3502D01*
G03X114802Y256979I-3502J1D01*
G02Y257141I183J81D01*
G03X115102Y258560I-3202J1418D01*
G03X114802Y259979I-3502J1D01*
G02Y260141I183J81D01*
G03X115102Y261560I-3202J1418D01*
G03X114529Y263481I-3502J1D01*
G01X114499Y263527D01*
X114494Y263637D01*
X114687Y263995D01*
G02X114863Y264100I176J-95D01*
G01X152389D01*
G02X152531Y264041I0J-200D01*
G01X153968Y262604D01*
G02X154027Y262462I-141J-142D01*
G01Y248224D01*
X153946Y248117D01*
X153882Y248099D01*
G03X151338Y244730I959J-3369D01*
G03X152046Y242618I3502J-1D01*
G02X152028Y242356I-160J-121D01*
G01X136086Y226414D01*
G03X135500Y225000I1413J-1414D01*
G01Y182811D01*
G03X136086Y181397I1999J0D01*
G01X225086Y92397D01*
G03X226500Y91811I1414J1413D01*
G01X582278D01*
G02X582420Y91752I0J-200D01*
G01X585441Y88731D01*
G02X585500Y88589I-141J-142D01*
G01Y7347D01*
G02X585441Y7205I-200J0D01*
G01X582295Y4059D01*
G02X582153Y4000I-142J141D01*
G01X575793D01*
G02X575651Y4059I0J200D01*
G03X573513I-1069J-1055D01*
G02X573371Y4000I-142J141D01*
G01X555793D01*
G02X555651Y4059I0J200D01*
G03X553513I-1069J-1055D01*
G02X553371Y4000I-142J141D01*
G01X535793D01*
G02X535651Y4059I0J200D01*
G03X533513I-1069J-1055D01*
G02X533371Y4000I-142J141D01*
G01X515793D01*
G02X515651Y4059I0J200D01*
G03X513513I-1069J-1055D01*
G02X513371Y4000I-142J141D01*
G01X495793D01*
G02X495651Y4059I0J200D01*
G03X493513I-1069J-1055D01*
G02X493371Y4000I-142J141D01*
G01X475793D01*
G02X475651Y4059I0J200D01*
G03X473513I-1069J-1055D01*
G02X473371Y4000I-142J141D01*
G01X455793D01*
G02X455651Y4059I0J200D01*
G03X453513I-1069J-1055D01*
G02X453371Y4000I-142J141D01*
G01X435793D01*
G02X435651Y4059I0J200D01*
G03X433513I-1069J-1055D01*
G02X433371Y4000I-142J141D01*
G01X415793D01*
G02X415651Y4059I0J200D01*
G03X413513I-1069J-1055D01*
G02X413371Y4000I-142J141D01*
G01X395793D01*
G02X395651Y4059I0J200D01*
G03X393513I-1069J-1055D01*
G02X393371Y4000I-142J141D01*
G01X375793D01*
G02X375651Y4059I0J200D01*
G03X373513I-1069J-1055D01*
G02X373371Y4000I-142J141D01*
G01X355793D01*
G02X355651Y4059I0J200D01*
G03X353513I-1069J-1055D01*
G02X353371Y4000I-142J141D01*
G01X335793D01*
G02X335651Y4059I0J200D01*
G03X333513I-1069J-1055D01*
G02X333371Y4000I-142J141D01*
G01X315793D01*
G02X315651Y4059I0J200D01*
G03X313513I-1069J-1055D01*
G02X313371Y4000I-142J141D01*
G01X295793D01*
G02X295651Y4059I0J200D01*
G03X293513I-1069J-1055D01*
G02X293371Y4000I-142J141D01*
G01X275793D01*
G02X275651Y4059I0J200D01*
G03X273513I-1069J-1055D01*
G02X273371Y4000I-142J141D01*
G01X255793D01*
G02X255651Y4059I0J200D01*
G03X253513I-1069J-1055D01*
G02X253371Y4000I-142J141D01*
G01X235793D01*
G02X235651Y4059I0J200D01*
G03X233513I-1069J-1055D01*
G02X233371Y4000I-142J141D01*
G01X215793D01*
G02X215651Y4059I0J200D01*
G03X213513I-1069J-1055D01*
G02X213371Y4000I-142J141D01*
G01X195793D01*
G02X195651Y4059I0J200D01*
G03X193513I-1069J-1055D01*
G02X193371Y4000I-142J141D01*
G01X175793D01*
G02X175651Y4059I0J200D01*
G03X173513I-1069J-1055D01*
G02X173371Y4000I-142J141D01*
G01X155793D01*
G02X155651Y4059I0J200D01*
G03X153513I-1069J-1055D01*
G02X153371Y4000I-142J141D01*
G01X135793D01*
G02X135651Y4059I0J200D01*
G03X133513I-1069J-1055D01*
G02X133371Y4000I-142J141D01*
G01X115793D01*
G02X115651Y4059I0J200D01*
G03X113513I-1069J-1055D01*
G02X113371Y4000I-142J141D01*
G01X95793D01*
G02X95651Y4059I0J200D01*
G03X93513I-1069J-1055D01*
G02X93371Y4000I-142J141D01*
G01X75793D01*
G02X75651Y4059I0J200D01*
G03X73513I-1069J-1055D01*
G02X73371Y4000I-142J141D01*
G01X55793D01*
G02X55651Y4059I0J200D01*
G03X53513I-1069J-1055D01*
G02X53371Y4000I-142J141D01*
G01X35793D01*
G02X35651Y4059I0J200D01*
G03X33513I-1069J-1055D01*
G02X33371Y4000I-142J141D01*
G01X19685D01*
G02X16244Y4382I0J15685D01*
G02X16115Y4478I45J195D01*
G03X14811Y5234I-1304J-747D01*
G03X14147Y5079I0J-1502D01*
G02X13986Y5072I-88J179D01*
G02X4036Y18619I5699J14613D01*
G02X4091Y18771I200J14D01*
G03X4507Y19808I-1086J1038D01*
G03X4060Y20878I-1502J1D01*
G02X4000Y21020I140J143D01*
G01Y33596D01*
G02X4060Y33738I200J-1D01*
G03X4507Y34808I-1055J1069D01*
G03X4060Y35878I-1502J1D01*
G02X4000Y36020I140J143D01*
G01Y58596D01*
G02X4060Y58738I200J-1D01*
G03X4507Y59808I-1055J1069D01*
G03X4060Y60878I-1502J1D01*
G02X4000Y61020I140J143D01*
G01Y63268D01*
G02X11551Y71075I7811J0D01*
G02X11699Y71015I5J-200D01*
G03X12767Y70570I1067J1057D01*
G03X13838Y71019I0J1502D01*
G02X13981Y71079I143J-140D01*
G01X37796D01*
G03X43372Y74918I0J5969D01*
G02X43558Y75047I187J-71D01*
G01X123047D01*
G03X124461Y75633I0J1999D01*
G01X126914Y78086D01*
G03X127500Y79500I-1413J1414D01*
G01Y120500D01*
G03X126914Y121914I-1999J0D01*
G01X125091Y123737D01*
G03X123677Y124323I-1414J-1413D01*
G01X43558D01*
G02X43372Y124452I1J200D01*
G03X37796Y128291I-5576J-2130D01*
G01X28485D01*
G02X28342Y128351I0J200D01*
G03X26200I-1071J-1053D01*
G02X26057Y128291I-143J140D01*
G01X11811D01*
G02X9126Y128767I0J7811D01*
G02X9006Y128887I68J188D01*
G03X7595Y129875I-1411J-514D01*
G03X7263Y129838I-1J-1502D01*
G02X7098Y129873I-45J195D01*
G02X4000Y136102I4713J6229D01*
G01Y144026D01*
G02X4060Y144168I200J-1D01*
G03X4507Y145238I-1055J1069D01*
G03X4060Y146308I-1502J1D01*
G02X4000Y146450I140J143D01*
G01Y164026D01*
G02X4060Y164168I200J-1D01*
G03X4507Y165238I-1055J1069D01*
G03X4060Y166308I-1502J1D01*
G02X4000Y166450I140J143D01*
G01Y184026D01*
G02X4060Y184168I200J-1D01*
G03X4507Y185238I-1055J1069D01*
G03X4060Y186308I-1502J1D01*
G02X4000Y186450I140J143D01*
G01Y204026D01*
G02X4060Y204168I200J-1D01*
G03X4507Y205238I-1055J1069D01*
G03X4060Y206308I-1502J1D01*
G02X4000Y206450I140J143D01*
G01Y224026D01*
G02X4060Y224168I200J-1D01*
G03X4507Y225238I-1055J1069D01*
G03X4060Y226308I-1502J1D01*
G02X4000Y226450I140J143D01*
G01Y244026D01*
G02X4060Y244168I200J-1D01*
G03X4507Y245238I-1055J1069D01*
G03X4060Y246308I-1502J1D01*
G02X4000Y246450I140J143D01*
G01Y264026D01*
G02X4060Y264168I200J-1D01*
G03X4507Y265238I-1055J1069D01*
G03X4060Y266308I-1502J1D01*
G02X4000Y266450I140J143D01*
G01Y284026D01*
G02X4060Y284168I200J-1D01*
G03X4507Y285238I-1055J1069D01*
G03X4060Y286308I-1502J1D01*
G02X4000Y286450I140J143D01*
G01Y304026D01*
G02X4060Y304168I200J-1D01*
G03X4507Y305238I-1055J1069D01*
G03X4060Y306308I-1502J1D01*
G02X4000Y306450I140J143D01*
G01Y324026D01*
G02X4060Y324168I200J-1D01*
G03X4507Y325238I-1055J1069D01*
G03X4060Y326308I-1502J1D01*
G02X4000Y326450I140J143D01*
G01Y344026D01*
G02X4060Y344168I200J-1D01*
G03X4507Y345238I-1055J1069D01*
G03X4060Y346308I-1502J1D01*
G02X4000Y346450I140J143D01*
G01Y364026D01*
G02X4060Y364168I200J-1D01*
G03X4507Y365238I-1055J1069D01*
G03X4060Y366308I-1502J1D01*
G02X4000Y366450I140J143D01*
G01Y384026D01*
G02X4060Y384168I200J-1D01*
G03X4507Y385238I-1055J1069D01*
G03X4060Y386308I-1502J1D01*
G02X4000Y386450I140J143D01*
G01Y404026D01*
G02X4060Y404168I200J-1D01*
G03X4507Y405238I-1055J1069D01*
G03X4060Y406308I-1502J1D01*
G02X4000Y406450I140J143D01*
G01Y424026D01*
G02X4060Y424168I200J-1D01*
G03X4507Y425238I-1055J1069D01*
G03X4060Y426308I-1502J1D01*
G02X4000Y426450I140J143D01*
G01Y444026D01*
G02X4060Y444168I200J-1D01*
G03X4507Y445238I-1055J1069D01*
G03X4083Y446284I-1502J0D01*
G02X4027Y446440I143J140D01*
G02X11811Y453598I7784J-653D01*
G01X18342D01*
G02X18485Y453538I0J-200D01*
G03X20631I1073J1051D01*
G02X20774Y453598I143J-140D01*
G01X37795D01*
G03X38639Y453658I0J5969D01*
G02X38771Y453631I28J-198D01*
G03X39549Y453414I778J1286D01*
G03X40982Y454465I0J1502D01*
G02X41063Y454572I191J-60D01*
G03X43764Y459567I-3268J4995D01*
G01Y504844D01*
G03X37796Y510811I-5968J-2D01*
G01X11811D01*
G02X11274Y510829I-7J7811D01*
G02X11126Y510911I14J200D01*
G03X9913Y511528I-1213J-884D01*
G03X9185Y511340I0J-1502D01*
G02X9017Y511328I-97J175D01*
G02X4000Y518622I2794J7294D01*
G01Y523083D01*
G02X4062Y523227I200J-1D01*
G03Y525397I-1040J1085D01*
G02X4000Y525541I138J145D01*
G01Y548083D01*
G02X4062Y548227I200J-1D01*
G03Y550397I-1040J1085D01*
G02X4000Y550541I138J145D01*
G01Y559055D01*
G02X4970Y564486I15685J1D01*
G02X5085Y564604I188J-68D01*
G03X6042Y566003I-544J1399D01*
G03X5957Y566502I-1502J1D01*
G02X5970Y566666I188J68D01*
G02X19290Y574735I13715J-7611D01*
G02X19436Y574677I5J-200D01*
G03X20498Y574237I1062J1062D01*
G03X21564Y574681I0J1502D01*
G02X21706Y574740I142J-141D01*
G01X39290D01*
G02X39432Y574681I0J-200D01*
G03X41564I1066J1058D01*
G02X41706Y574740I142J-141D01*
G01X59290D01*
G02X59432Y574681I0J-200D01*
G03X61564I1066J1058D01*
G02X61706Y574740I142J-141D01*
G01X79290D01*
G02X79432Y574681I0J-200D01*
G03X81564I1066J1058D01*
G02X81706Y574740I142J-141D01*
G01X99290D01*
G02X99432Y574681I0J-200D01*
G03X101564I1066J1058D01*
G02X101706Y574740I142J-141D01*
G01X119290D01*
G02X119432Y574681I0J-200D01*
G03X121564I1066J1058D01*
G02X121706Y574740I142J-141D01*
G01X139290D01*
G02X139432Y574681I0J-200D01*
G03X141564I1066J1058D01*
G02X141706Y574740I142J-141D01*
G37*
G36*
G01X64877Y466181D02*
X134720D01*
G02X134862Y466122I0J-200D01*
G01X137751Y463233D01*
G02X137810Y463091I-141J-142D01*
G01Y333790D01*
G03X138396Y332376I1999J0D01*
G01X144186Y326586D01*
G03X145600Y326000I1414J1413D01*
G01X158323D01*
G02X158503Y325888I0J-200D01*
G01X158686Y325513D01*
X158674Y325400D01*
X158638Y325354D01*
G03X157898Y323200I2762J-2153D01*
G03X164902I3502J0D01*
G03X164162Y325354I-3502J1D01*
G01X164126Y325400D01*
X164114Y325513D01*
X164297Y325888D01*
G02X164477Y326000I180J-88D01*
G01X174686D01*
G02X174828Y325941I0J-200D01*
G01X176537Y324232D01*
G02X176596Y324090I-141J-142D01*
G01Y323125D01*
G02X176537Y322983I-200J0D01*
G01X149586Y296032D01*
G03X149000Y294618I1413J-1414D01*
G01Y270411D01*
G02X148941Y270269I-200J0D01*
G01X146831Y268159D01*
G02X146689Y268100I-142J141D01*
G01X36811D01*
G02X36669Y268159I0J200D01*
G01X34159Y270669D01*
G02X34100Y270811I141J142D01*
G01Y302989D01*
G02X34159Y303131I200J0D01*
G01X35869Y304841D01*
G02X36011Y304900I142J-141D01*
G01X58900D01*
G03X60314Y305486I0J1999D01*
G01X61414Y306586D01*
G03X62000Y308000I-1413J1414D01*
G01Y463304D01*
G02X62059Y463446I200J0D01*
G01X64735Y466122D01*
G02X64877Y466181I142J-141D01*
G37*
G36*
G01X786529Y259151D02*
Y259150D01*
G03X793471I3471J462D01*
G01Y259151D01*
G02X793669Y259324I198J-27D01*
G01X794175D01*
G02X794374Y259146I0J-200D01*
G03X797854Y256036I3480J392D01*
G03X800382Y257115I-1J3503D01*
G01X800411Y257145D01*
X800485Y257177D01*
X800817Y257175D01*
G02X800961Y257113I-1J-200D01*
G03X803500Y256023I2539J2412D01*
G03X806157Y257243I0J3503D01*
G01X806186Y257278D01*
X806267Y257314D01*
X806619Y257309D01*
G02X806772Y257234I-3J-200D01*
G03X809500Y255928I2728J2196D01*
G03X812991Y259141I0J3503D01*
G01X812997Y259218D01*
X813112Y259324D01*
X822573D01*
G02X822758Y259200I0J-200D01*
G03X826000Y257022I3242J1324D01*
G03X828296Y257880I-1J3503D01*
G02X828429Y257929I131J-151D01*
G01X828546D01*
G02X828677Y257878I-2J-200D01*
G03X830998Y256998I2322J2622D01*
G01X831000D01*
G03X833310Y257867I1J3503D01*
G02X833441Y257917I132J-150D01*
G01X833559D01*
G02X833690Y257867I-1J-200D01*
G03X836000Y256998I2309J2634D01*
G01X836001D01*
G03X837741Y257461I0J3502D01*
G02X837982Y257429I100J-173D01*
G01X841053Y254358D01*
G02X841112Y254216I-141J-142D01*
G01Y188642D01*
G02X841053Y188500I-200J0D01*
G01X836233Y183680D01*
G02X836091Y183621I-142J141D01*
G01X807563D01*
G03X806149Y183035I0J-1999D01*
G01X802586Y179472D01*
G03X802000Y178058I1413J-1414D01*
G01Y101911D01*
G02X801941Y101769I-200J0D01*
G01X796042Y95870D01*
G02X795900Y95811I-142J141D01*
G01X227411D01*
G02X227269Y95870I0J200D01*
G01X139559Y183580D01*
G02X139500Y183722I141J142D01*
G01Y224089D01*
G02X139559Y224231I200J0D01*
G01X152755Y237427D01*
G02X153018Y237445I142J-141D01*
G03X155140Y236728I2123J2785D01*
G03X158642Y240230I0J3502D01*
G03X157854Y242444I-3504J0D01*
G02X157828Y242658I154J127D01*
G03X158001Y243202I-1799J872D01*
G02X158017Y243254I197J-32D01*
G03X158342Y244730I-3178J1473D01*
G03X158044Y246145I-3502J1D01*
G02X158027Y246226I183J81D01*
G01Y263562D01*
G02X158086Y263704I200J0D01*
G01X161823Y267441D01*
G02X161965Y267500I142J-141D01*
G01X194695D01*
G02X194835Y267443I0J-200D01*
G01X195064Y267218D01*
X195095Y267147D01*
Y267108D01*
G03X200197Y262102I5102J97D01*
G01X200199D01*
G03X203848Y263639I-1J5102D01*
G02X203992Y263700I144J-139D01*
G01X204276D01*
G02X204420Y263639I0J-200D01*
G03X208071Y262102I3650J3565D01*
G03X211722Y263639I1J5102D01*
G02X211866Y263700I144J-139D01*
G01X212150D01*
G02X212294Y263639I0J-200D01*
G03X215945Y262102I3650J3565D01*
G03X219596Y263639I1J5102D01*
G02X219740Y263700I144J-139D01*
G01X220024D01*
G02X220168Y263639I0J-200D01*
G03X223819Y262102I3650J3565D01*
G03X227470Y263639I1J5102D01*
G02X227614Y263700I144J-139D01*
G01X227898D01*
G02X228042Y263639I0J-200D01*
G03X231693Y262102I3650J3565D01*
G03X235344Y263639I1J5102D01*
G02X235488Y263700I144J-139D01*
G01X235772D01*
G02X235916Y263639I0J-200D01*
G03X239567Y262102I3650J3565D01*
G03X243218Y263639I1J5102D01*
G02X243362Y263700I144J-139D01*
G01X243646D01*
G02X243790Y263639I0J-200D01*
G03X247439Y262102I3650J3565D01*
G01X247441D01*
G03Y272306I0J5102D01*
G01X247439D01*
G03X243790Y270769I1J-5102D01*
G02X243646Y270708I-144J139D01*
G01X243362D01*
G02X243218Y270769I0J200D01*
G03X239567Y272306I-3650J-3565D01*
G03X235916Y270769I-1J-5102D01*
G02X235772Y270708I-144J139D01*
G01X235488D01*
G02X235344Y270769I0J200D01*
G03X231693Y272306I-3650J-3565D01*
G03X228042Y270769I-1J-5102D01*
G02X227898Y270708I-144J139D01*
G01X227614D01*
G02X227470Y270769I0J200D01*
G03X223819Y272306I-3650J-3565D01*
G03X220168Y270769I-1J-5102D01*
G02X220024Y270708I-144J139D01*
G01X219740D01*
G02X219596Y270769I0J200D01*
G03X215945Y272306I-3650J-3565D01*
G03X212294Y270769I-1J-5102D01*
G02X212150Y270708I-144J139D01*
G01X211866D01*
G02X211722Y270769I0J200D01*
G03X208071Y272306I-3650J-3565D01*
G03X204420Y270769I-1J-5102D01*
G02X204276Y270708I-144J139D01*
G01X203992D01*
G02X203848Y270769I0J200D01*
G03X202095Y271940I-3650J-3566D01*
G01X202048Y271959D01*
X201984Y272036D01*
X201907Y272413D01*
G02X201961Y272594I196J40D01*
G01X221926Y292559D01*
G02X222068Y292618I142J-141D01*
G01X308050D01*
G02X308192Y292559I0J-200D01*
G01X340841Y259910D01*
G03X342255Y259324I1414J1413D01*
G01X786331D01*
G02X786529Y259151I0J-200D01*
G37*
G36*
G01X861166Y357426D02*
X861187Y357365D01*
G03X863838Y355061I3313J1135D01*
G01X863909Y355047D01*
X864000Y354937D01*
Y316637D01*
X863926Y316534D01*
X863865Y316513D01*
G03Y309887I1135J-3313D01*
G01X863926Y309866D01*
X864000Y309763D01*
Y293122D01*
G02X863973Y293021I-200J-1D01*
G03Y289499I3028J-1761D01*
G02X864000Y289398I-173J-100D01*
G01Y286341D01*
G03X864586Y284927I1999J0D01*
G01X901167Y248346D01*
G02X901212Y248133I-142J-141D01*
G01X901060Y247736D01*
X900963Y247667D01*
X900904Y247664D01*
G03X882198Y228001I981J-19663D01*
G03X901884Y208314I19687J0D01*
G01X988501D01*
G03X1002917Y214594I0J19687D01*
G01X1002945Y214624D01*
X1003019Y214657D01*
X1003348Y214663D01*
G02X1003493Y214604I3J-200D01*
G01X1016206Y201891D01*
G02X1016256Y201689I-141J-142D01*
G01X1016149Y201351D01*
G02X1015995Y201214I-191J60D01*
G01X1015994D01*
G03X1013112Y197767I620J-3447D01*
G01Y197763D01*
G03X1013413Y196345I3502J3D01*
G02Y196183I-183J-81D01*
G03X1013114Y194768I3201J-1415D01*
G01Y194767D01*
G03X1013834Y192641I3501J1D01*
G02Y192398I-159J-122D01*
G03X1013112Y190267I2780J-2130D01*
G03X1013412Y188848I3502J-1D01*
G02Y188686I-183J-81D01*
G03X1013112Y187269I3202J-1418D01*
G01Y187267D01*
G03X1020116I3502J0D01*
G01Y187269D01*
G03X1019816Y188686I-3502J-1D01*
G02Y188848I183J81D01*
G03X1020116Y190267I-3202J1418D01*
G03X1019394Y192398I-3502J1D01*
G02Y192641I159J121D01*
G03X1020114Y194767I-2781J2127D01*
G01Y194768D01*
G03X1019815Y196183I-3500J0D01*
G02Y196345I183J81D01*
G03X1020116Y197767I-3201J1421D01*
G03X1019023Y200310I-3502J1D01*
G01X1018978Y200352D01*
X1018951Y200472D01*
X1019112Y200874D01*
G02X1019298Y201000I186J-74D01*
G01X1064589D01*
G02X1064731Y200941I0J-200D01*
G01X1067941Y197731D01*
G02X1068000Y197589I-141J-142D01*
G01Y195116D01*
G02X1067996Y195078I-200J2D01*
G02X1067789Y194917I-196J38D01*
G02X1067757Y194921I9J200D01*
G03X1067000Y195004I-758J-3421D01*
G03Y187996I0J-3504D01*
G03X1067757Y188079I-1J3504D01*
G02X1067789Y188083I41J-196D01*
G02X1067996Y187922I11J-199D01*
G02X1068000Y187884I-196J-40D01*
G01Y180867D01*
G02X1067957Y180744I-200J1D01*
G03Y176426I2758J-2159D01*
G02X1068000Y176303I-157J-124D01*
G01Y170000D01*
G03X1068586Y168586I1999J0D01*
G01X1077586Y159586D01*
G03X1079000Y159000I1414J1413D01*
G01X1080804D01*
X1080916Y158901D01*
X1080926Y158825D01*
G03X1087876I3475J435D01*
G01X1087886Y158901D01*
X1087998Y159000D01*
X1088437D01*
X1088547Y158909D01*
X1088561Y158838D01*
G03X1095439I3439J662D01*
G01X1095453Y158909D01*
X1095563Y159000D01*
X1110589D01*
G02X1110731Y158941I0J-200D01*
G01X1115441Y154231D01*
G02X1115500Y154089I-141J-142D01*
G01Y137311D01*
G02X1115441Y137169I-200J0D01*
G01X1111831Y133559D01*
G02X1111689Y133500I-142J141D01*
G01X1085491D01*
X1085459Y133511D01*
G03X1084325Y133700I-1135J-3314D01*
G03X1083191Y133511I1J-3503D01*
G01X1083159Y133500D01*
X1064600D01*
G03X1063186Y132914I0J-1999D01*
G01X1058331Y128059D01*
G02X1058189Y128000I-142J141D01*
G01X973011D01*
G02X972869Y128059I0J200D01*
G01X944514Y156414D01*
G03X943100Y157000I-1414J-1413D01*
G01X850100D01*
G03X848686Y156414I0J-1999D01*
G01X845186Y152914D01*
G03X844600Y151500I1413J-1414D01*
G01Y90000D01*
G03X845186Y88586I1999J0D01*
G01X849686Y84086D01*
G03X851100Y83500I1414J1413D01*
G01X1069589D01*
G02X1069731Y83441I0J-200D01*
G01X1073941Y79231D01*
G02X1074000Y79089I-141J-142D01*
G01Y6911D01*
G02X1073941Y6769I-200J0D01*
G01X1073510Y6338D01*
X1073466Y6323D01*
G03X1071268Y4135I1116J-3319D01*
G01X1071263Y4120D01*
G02X1071215Y4043I-189J65D01*
G01X1071202Y4030D01*
X1071129Y4000D01*
X1058020D01*
X1057917Y4074D01*
X1057896Y4135D01*
G03X1051268I-3314J-1131D01*
G01X1051247Y4074D01*
X1051144Y4000D01*
X1038020D01*
X1037917Y4074D01*
X1037896Y4135D01*
G03X1031268I-3314J-1131D01*
G01X1031247Y4074D01*
X1031144Y4000D01*
X1018020D01*
X1017917Y4074D01*
X1017896Y4135D01*
G03X1011268I-3314J-1131D01*
G01X1011247Y4074D01*
X1011144Y4000D01*
X998020D01*
X997917Y4074D01*
X997896Y4135D01*
G03X991268I-3314J-1131D01*
G01X991247Y4074D01*
X991144Y4000D01*
X978020D01*
X977917Y4074D01*
X977896Y4135D01*
G03X971268I-3314J-1131D01*
G01X971247Y4074D01*
X971144Y4000D01*
X958020D01*
X957917Y4074D01*
X957896Y4135D01*
G03X951268I-3314J-1131D01*
G01X951247Y4074D01*
X951144Y4000D01*
X938020D01*
X937917Y4074D01*
X937896Y4135D01*
G03X931268I-3314J-1131D01*
G01X931247Y4074D01*
X931144Y4000D01*
X918020D01*
X917917Y4074D01*
X917896Y4135D01*
G03X911268I-3314J-1131D01*
G01X911247Y4074D01*
X911144Y4000D01*
X898020D01*
X897917Y4074D01*
X897896Y4135D01*
G03X891268I-3314J-1131D01*
G01X891247Y4074D01*
X891144Y4000D01*
X878020D01*
X877917Y4074D01*
X877896Y4135D01*
G03X871268I-3314J-1131D01*
G01X871247Y4074D01*
X871144Y4000D01*
X858020D01*
X857917Y4074D01*
X857896Y4135D01*
G03X851268I-3314J-1131D01*
G01X851247Y4074D01*
X851144Y4000D01*
X838020D01*
X837917Y4074D01*
X837896Y4135D01*
G03X831268I-3314J-1131D01*
G01X831247Y4074D01*
X831144Y4000D01*
X818020D01*
X817917Y4074D01*
X817896Y4135D01*
G03X811268I-3314J-1131D01*
G01X811247Y4074D01*
X811144Y4000D01*
X798020D01*
X797917Y4074D01*
X797896Y4135D01*
G03X791268I-3314J-1131D01*
G01X791247Y4074D01*
X791144Y4000D01*
X778020D01*
X777917Y4074D01*
X777896Y4135D01*
G03X771268I-3314J-1131D01*
G01X771247Y4074D01*
X771144Y4000D01*
X758020D01*
X757917Y4074D01*
X757896Y4135D01*
G03X751268I-3314J-1131D01*
G01X751247Y4074D01*
X751144Y4000D01*
X738020D01*
X737917Y4074D01*
X737896Y4135D01*
G03X731268I-3314J-1131D01*
G01X731247Y4074D01*
X731144Y4000D01*
X718020D01*
X717917Y4074D01*
X717896Y4135D01*
G03X711268I-3314J-1131D01*
G01X711247Y4074D01*
X711144Y4000D01*
X698020D01*
X697917Y4074D01*
X697896Y4135D01*
G03X691268I-3314J-1131D01*
G01X691247Y4074D01*
X691144Y4000D01*
X678020D01*
X677917Y4074D01*
X677896Y4135D01*
G03X671268I-3314J-1131D01*
G01X671247Y4074D01*
X671144Y4000D01*
X658020D01*
X657917Y4074D01*
X657896Y4135D01*
G03X651268I-3314J-1131D01*
G01X651247Y4074D01*
X651144Y4000D01*
X638020D01*
X637917Y4074D01*
X637896Y4135D01*
G03X631268I-3314J-1131D01*
G01X631247Y4074D01*
X631144Y4000D01*
X618020D01*
X617917Y4074D01*
X617896Y4135D01*
G03X611268I-3314J-1131D01*
G01X611247Y4074D01*
X611144Y4000D01*
X598020D01*
X597917Y4074D01*
X597896Y4135D01*
G03X594582Y6506I-3314J-1131D01*
G01X594581D01*
G03X591993Y5363I0J-3502D01*
G01X591966Y5333D01*
X591891Y5298D01*
X591560Y5291D01*
G02X591415Y5349I-4J200D01*
G01X589559Y7205D01*
G02X589500Y7347I141J142D01*
G01Y88589D01*
G02X589559Y88731I200J0D01*
G01X592580Y91752D01*
G02X592722Y91811I142J-141D01*
G01X796811D01*
G03X798225Y92397I0J1999D01*
G01X805414Y99586D01*
G03X806000Y101000I-1413J1414D01*
G01Y177147D01*
G02X806059Y177289I200J0D01*
G01X808332Y179562D01*
G02X808474Y179621I142J-141D01*
G01X837002D01*
G03X838416Y180207I0J1999D01*
G01X844526Y186317D01*
G03X845112Y187731I-1413J1414D01*
G01Y255127D01*
G03X844526Y256541I-1999J0D01*
G01X839243Y261824D01*
X839228Y261860D01*
G03X836000Y264002I-3228J-1361D01*
G01X835997D01*
G03X833979Y263361I2J-3502D01*
G01X833953Y263343D01*
X833895Y263324D01*
X833105D01*
X833047Y263343D01*
X833021Y263361D01*
G03X831000Y264002I-2020J-2861D01*
G03X828979Y263361I-1J-3502D01*
G01X828953Y263343D01*
X828895Y263324D01*
X828139D01*
X828079Y263343D01*
X828054Y263362D01*
G03X826000Y264028I-2055J-2837D01*
G03X823947Y263362I2J-3502D01*
G02X823829Y263324I-117J162D01*
G01X343166D01*
G02X343024Y263383I0J200D01*
G01X310375Y296032D01*
G03X308961Y296618I-1414J-1413D01*
G01X221157D01*
G03X219743Y296032I0J-1999D01*
G01X195270Y271559D01*
G02X195128Y271500I-142J141D01*
G01X156938D01*
G02X156796Y271559I0J200D01*
G01X153059Y275296D01*
G02X153000Y275438I141J142D01*
G01Y293707D01*
G02X153059Y293849I200J0D01*
G01X185151Y325941D01*
G02X185293Y326000I142J-141D01*
G01X587000D01*
G03X588414Y326586I0J1999D01*
G01X619269Y357441D01*
G02X619411Y357500I142J-141D01*
G01X700934D01*
G02X701121Y357370I0J-200D01*
G03X701163Y357262I3285J1215D01*
G02X701122Y357046I-185J-77D01*
G03X700698Y356000I1078J-1046D01*
G03X702200Y354498I1502J0D01*
G03X703411Y355110I0J1504D01*
G02X703616Y355187I161J-118D01*
G03X704400Y355098I785J3413D01*
G03X706125Y355552I1J3501D01*
G02X706306Y355560I98J-174D01*
G03X707750Y355248I1445J3190D01*
G03X710972Y357378I0J3502D01*
G02X711156Y357500I184J-78D01*
G01X788437D01*
X788547Y357409D01*
X788561Y357338D01*
G03X795439I3439J662D01*
G01X795453Y357409D01*
X795563Y357500D01*
X848050D01*
G02X848183Y357450I1J-200D01*
G03X848895Y356963I2317J2624D01*
G02X849003Y356801I-91J-178D01*
G03X851997I1497J124D01*
G02X852105Y356963I199J-16D01*
G03X852817Y357450I-1605J3111D01*
G02X852950Y357500I132J-150D01*
G01X861063D01*
X861166Y357426D01*
G37*
G36*
G01X931500Y362498D02*
G03X931726Y362505I5J3502D01*
G01X931727D01*
G02X931894Y362432I12J-200D01*
G01X932131Y362141D01*
X932151Y362047D01*
X932138Y362000D01*
G03X932014Y361078I3378J-924D01*
G01Y361075D01*
G03X939018I3502J0D01*
G01Y361079D01*
G03X938747Y362428I-3502J-2D01*
G02X938798Y362654I184J77D01*
G01X939078Y362907D01*
G02X939309Y362933I134J-149D01*
G03X941000Y362498I1690J3067D01*
G03X942419Y362798I1J3502D01*
G02X942581I81J-183D01*
G03X944000Y362498I1418J3202D01*
G03X946917Y364061I1J3502D01*
G01X946945Y364102D01*
X947033Y364150D01*
X947467D01*
X947555Y364102D01*
X947583Y364061D01*
G03X950500Y362498I2916J1939D01*
G03X951919Y362798I1J3502D01*
G02X952081I81J-183D01*
G03X953498Y362498I1418J3202D01*
G01X953500D01*
G03Y369502I0J3502D01*
G01X953498D01*
G03X952081Y369202I1J-3502D01*
G02X951919I-81J183D01*
G03X950500Y369502I-1418J-3202D01*
G03X947583Y367939I-1J-3502D01*
G01X947555Y367898D01*
X947467Y367850D01*
X947033D01*
X946945Y367898D01*
X946917Y367939D01*
G03X944000Y369502I-2916J-1939D01*
G03X942581Y369202I-1J-3502D01*
G02X942419I-81J183D01*
G03X941000Y369502I-1418J-3202D01*
G03X938083Y367939I-1J-3502D01*
G01X938055Y367898D01*
X937967Y367850D01*
X937533D01*
X937445Y367898D01*
X937417Y367939D01*
G03X934500Y369502I-2916J-1939D01*
G03X933081Y369202I-1J-3502D01*
G02X932919I-81J183D01*
G03X931500Y369502I-1418J-3202D01*
G03X928583Y367939I-1J-3502D01*
G01X928555Y367898D01*
X928467Y367850D01*
X928033D01*
X927945Y367898D01*
X927917Y367939D01*
G03X925000Y369502I-2916J-1939D01*
G03X923581Y369202I-1J-3502D01*
G02X923419I-81J183D01*
G03X922000Y369502I-1418J-3202D01*
G03X919083Y367939I-1J-3502D01*
G01X919055Y367898D01*
X918967Y367850D01*
X918533D01*
X918445Y367898D01*
X918417Y367939D01*
G03X915500Y369502I-2916J-1939D01*
G03X914081Y369202I-1J-3502D01*
G02X913919I-81J183D01*
G03X912500Y369502I-1418J-3202D01*
G03X909583Y367939I-1J-3502D01*
G01X909555Y367898D01*
X909467Y367850D01*
X909033D01*
X908945Y367898D01*
X908917Y367939D01*
G03X906000Y369502I-2916J-1939D01*
G03X904581Y369202I-1J-3502D01*
G02X904419I-81J183D01*
G03X903000Y369502I-1418J-3202D01*
G03X900083Y367939I-1J-3502D01*
G01X900055Y367898D01*
X899967Y367850D01*
X899533D01*
X899445Y367898D01*
X899417Y367939D01*
G03X896500Y369502I-2916J-1939D01*
G03X895081Y369202I-1J-3502D01*
G02X894919I-81J183D01*
G03X893500Y369502I-1418J-3202D01*
G03X890583Y367939I-1J-3502D01*
G01X890555Y367898D01*
X890467Y367850D01*
X890033D01*
X889945Y367898D01*
X889917Y367939D01*
G03X887000Y369502I-2916J-1939D01*
G03X885581Y369202I-1J-3502D01*
G02X885419I-81J183D01*
G03X884000Y369502I-1418J-3202D01*
G03X881083Y367939I-1J-3502D01*
G01X881055Y367898D01*
X880967Y367850D01*
X880533D01*
X880445Y367898D01*
X880417Y367939D01*
G03X877500Y369502I-2916J-1939D01*
G03X876081Y369202I-1J-3502D01*
G02X875919I-81J183D01*
G03X874500Y369502I-1418J-3202D01*
G03X871807Y368240I-1J-3502D01*
G01X871779Y368206D01*
X871699Y368168D01*
X871301D01*
X871221Y368206D01*
X871193Y368240D01*
G03X868500Y369502I-2692J-2240D01*
G03X867081Y369202I-1J-3502D01*
G02X866919I-81J183D01*
G03X865500Y369502I-1418J-3202D01*
G03X862807Y368240I-1J-3502D01*
G01X862779Y368206D01*
X862699Y368168D01*
X862301D01*
X862221Y368206D01*
X862193Y368240D01*
G03X859500Y369502I-2692J-2240D01*
G03X858081Y369202I-1J-3502D01*
G02X857919I-81J183D01*
G03X856500Y369502I-1418J-3202D01*
G03X853807Y368240I-1J-3502D01*
G01X853779Y368206D01*
X853699Y368168D01*
X853301D01*
X853221Y368206D01*
X853193Y368240D01*
G03X850500Y369502I-2692J-2240D01*
G03X849081Y369202I-1J-3502D01*
G02X848919I-81J183D01*
G03X847502Y369502I-1418J-3202D01*
G01X847500D01*
G03X843998Y366000I0J-3502D01*
G03X847205Y362510I3502J0D01*
G01X847257Y362506D01*
X847343Y362448D01*
X847544Y362051D01*
X847540Y361948D01*
X847513Y361903D01*
G03X847353Y361612I2985J-1831D01*
G02X847174Y361500I-180J88D01*
G01X830494D01*
G02X830305Y361634I0J200D01*
G03X823695I-3305J-1159D01*
G02X823506Y361500I-189J66D01*
G01X817876D01*
G02X817733Y361560I0J200D01*
G01X817504Y361795D01*
X817475Y361869D01*
X817476Y361910D01*
G03X817478Y361999I-3500J123D01*
G01Y362001D01*
G03X810472I-3503J-1D01*
G01Y361999D01*
G03X810474Y361911I3502J36D01*
G01Y361909D01*
X810475Y361869D01*
X810446Y361795D01*
X810217Y361560D01*
G02X810074Y361500I-143J140D01*
G01X806876D01*
G02X806733Y361560I0J200D01*
G01X806504Y361795D01*
X806475Y361869D01*
X806476Y361910D01*
G03X806478Y361999I-3500J123D01*
G01Y362001D01*
G03X799472I-3503J-1D01*
G01Y361999D01*
G03X799474Y361911I3502J36D01*
G01Y361909D01*
X799475Y361869D01*
X799446Y361795D01*
X799217Y361560D01*
G02X799074Y361500I-143J140D01*
G01X792118D01*
X792112D01*
G03X792000Y361502I-119J-3500D01*
G03X791888Y361500I7J-3502D01*
G01X785319D01*
G02X785164Y361574I0J200D01*
G01X784968Y361816D01*
G02X784928Y361982I156J125D01*
G03X785002Y362696I-3428J716D01*
G01Y362700D01*
G03X777998I-3502J0D01*
G01Y362696D01*
G03X778072Y361982I3502J2D01*
G02X778032Y361816I-196J-41D01*
G01X777836Y361574D01*
G02X777681Y361500I-155J126D01*
G01X746197D01*
G02X745997Y361688I0J200D01*
G01Y361689D01*
G03X739003I-3497J-189D01*
G01Y361688D01*
G02X738803Y361500I-200J12D01*
G01X709986D01*
G02X709865Y361541I0J200D01*
G03X707750Y362252I-2115J-2790D01*
G03X706025Y361798I-1J-3501D01*
G02X705844Y361790I-98J174D01*
G03X704400Y362102I-1445J-3190D01*
G03X702486Y361533I-1J-3502D01*
G02X702377Y361500I-110J167D01*
G01X618500D01*
G03X617086Y360914I0J-1999D01*
G01X586231Y330059D01*
G02X586089Y330000I-142J141D01*
G01X146511D01*
G02X146369Y330059I0J200D01*
G01X141869Y334559D01*
G02X141810Y334701I141J142D01*
G01Y463091D01*
G02X141869Y463233I200J0D01*
G01X144758Y466122D01*
G02X144900Y466181I142J-141D01*
G01X874643D01*
G03X876057Y466767I0J1999D01*
G01X880377Y471087D01*
G03X880963Y472501I-1413J1414D01*
G01Y549905D01*
G02X881086Y550089I200J0D01*
G03Y567151I-3576J8531D01*
G02X880963Y567335I77J184D01*
G01Y570833D01*
G02X881022Y570975I200J0D01*
G01X884728Y574681D01*
G02X884870Y574740I142J-141D01*
G01X936996D01*
G02X937185Y574606I0J-200D01*
G01Y574605D01*
G03X943811I3313J1134D01*
G01Y574606D01*
G02X944000Y574740I189J-66D01*
G01X956996D01*
G02X957185Y574606I0J-200D01*
G01Y574605D01*
G03X963811I3313J1134D01*
G01Y574606D01*
G02X964000Y574740I189J-66D01*
G01X976996D01*
G02X977185Y574606I0J-200D01*
G01Y574605D01*
G03X983811I3313J1134D01*
G01Y574606D01*
G02X984000Y574740I189J-66D01*
G01X996996D01*
G02X997185Y574606I0J-200D01*
G01Y574605D01*
G03X1003811I3313J1134D01*
G01Y574606D01*
G02X1004000Y574740I189J-66D01*
G01X1016996D01*
G02X1017185Y574606I0J-200D01*
G01Y574605D01*
G03X1023811I3313J1134D01*
G01Y574606D01*
G02X1024000Y574740I189J-66D01*
G01X1036996D01*
G02X1037185Y574606I0J-200D01*
G01Y574605D01*
G03X1043811I3313J1134D01*
G01Y574606D01*
G02X1044000Y574740I189J-66D01*
G01X1056996D01*
G02X1057185Y574606I0J-200D01*
G01Y574605D01*
G03X1063811I3313J1134D01*
G01Y574606D01*
G02X1064000Y574740I189J-66D01*
G01X1076996D01*
G02X1077185Y574606I0J-200D01*
G01Y574605D01*
G03X1083811I3313J1134D01*
G01Y574606D01*
G02X1084000Y574740I189J-66D01*
G01X1090491D01*
G02X1090633Y574681I0J-200D01*
G01X1093216Y572098D01*
G02X1093275Y571956I-141J-142D01*
G01Y420395D01*
G02X1093162Y420215I-200J0D01*
G01X1092784Y420033D01*
X1092672Y420046D01*
X1092626Y420082D01*
G03X1090443Y420846I-2184J-2739D01*
G03Y413840I0J-3503D01*
G03X1092626Y414604I-1J3503D01*
G01X1092672Y414640D01*
X1092784Y414653D01*
X1093162Y414471D01*
G02X1093275Y414291I-87J-180D01*
G01Y379596D01*
G02X1093164Y379417I-200J0D01*
G01X1092790Y379233D01*
X1092677Y379244D01*
X1092632Y379279D01*
G03X1090502Y380002I-2131J-2779D01*
G01X1090500D01*
G03Y372998I0J-3502D01*
G01X1090502D01*
G03X1092632Y373721I-1J3502D01*
G01X1092677Y373756D01*
X1092790Y373767D01*
X1093164Y373583D01*
G02X1093275Y373404I-89J-179D01*
G01Y212225D01*
G03X1093861Y210811I1999J0D01*
G01X1096890Y207782D01*
G02X1096941Y207586I-141J-141D01*
G01X1096830Y207197D01*
X1096753Y207123D01*
X1096699Y207110D01*
G03X1093998Y203700I802J-3410D01*
G03X1097500Y200198I3502J0D01*
G01X1097503D01*
G03X1098683Y200403I-1J3502D01*
G02X1098817I67J-188D01*
G03X1100000Y200198I1181J3297D01*
G03X1102652Y201412I1J3502D01*
G02X1102796Y201481I151J-131D01*
G01X1103089Y201493D01*
G02X1103238Y201434I7J-200D01*
G01X1112514Y192158D01*
G02X1112572Y191999I-141J-142D01*
G01X1112547Y191696D01*
G02X1112464Y191550I-199J17D01*
G03X1110998Y188700I2037J-2850D01*
G03X1114500Y185198I3502J0D01*
G01X1114501D01*
G03X1117111Y186366I-1J3502D01*
G02X1117354Y186409I149J-134D01*
G03X1119000Y185998I1646J3091D01*
G01X1119002D01*
G03X1119831Y186098I-2J3502D01*
G02X1119976Y186078I47J-194D01*
G01X1120079Y186021D01*
G02X1120172Y185908I-97J-175D01*
G03X1123500Y183498I3328J1093D01*
G03X1127002Y187000I0J3502D01*
G01Y187001D01*
G03X1125219Y190052I-3502J0D01*
G01X1125160Y190085D01*
X1125107Y190210D01*
X1125222Y190651D01*
G02X1125415Y190800I193J-51D01*
G01X1162825D01*
G02X1162967Y190741I0J-200D01*
G01X1163641Y190067D01*
G02X1163700Y189925I-141J-142D01*
G01Y167111D01*
G02X1163641Y166969I-200J0D01*
G01X1159731Y163059D01*
G02X1159589Y163000I-142J141D01*
G01X1155920D01*
G02X1155742Y163110I1J200D01*
G01X1155580Y163429D01*
G02X1155598Y163638I179J90D01*
G03X1156284Y165719I-2817J2082D01*
G03X1149278I-3503J0D01*
G03X1149964Y163638I3503J1D01*
G01X1149998Y163592D01*
X1150007Y163480D01*
X1149820Y163110D01*
G02X1149642Y163000I-179J90D01*
G01X1143500D01*
G03X1143116Y162962I4J-1999D01*
G02X1142911Y163047I-39J196D01*
G03X1140000Y164602I-2911J-1947D01*
G01X1139998D01*
G03X1138250Y164134I1J-3502D01*
G02X1138050I-100J173D01*
G03X1136302Y164602I-1749J-3034D01*
G01X1136300D01*
G03Y157598I0J-3502D01*
G01X1136302D01*
G03X1138050Y158066I-1J3502D01*
G02X1138250I100J-173D01*
G03X1138392Y157989I1740J3040D01*
G02X1138500Y157811I-92J-178D01*
G01Y136437D01*
G02X1138473Y136336I-200J-1D01*
G03Y132814I3028J-1761D01*
G02X1138500Y132713I-173J-100D01*
G01Y126287D01*
G02X1138473Y126186I-200J-1D01*
G03Y122664I3027J-1761D01*
G01X1138486Y122641D01*
X1138500Y122591D01*
Y122334D01*
X1138486Y122284D01*
X1138473Y122261D01*
G03X1137998Y120500I3027J-1761D01*
G01Y120498D01*
G03X1138370Y118928I3502J1D01*
G01X1138399Y118870D01*
X1138379Y118743D01*
X1138195Y118559D01*
G02X1138053Y118500I-142J141D01*
G01X1120411D01*
G02X1120269Y118559I0J200D01*
G01X1119559Y119269D01*
G02X1119500Y119411I141J142D01*
G01Y134605D01*
G02X1119570Y134757I200J0D01*
G01X1119803Y134955D01*
G02X1119963Y135000I129J-153D01*
G01X1119964D01*
G03X1120524Y134954I566J3457D01*
G03X1122118Y135338I-1J3503D01*
G01X1122119D01*
G02X1122292Y135343I92J-178D01*
G01X1122617Y135196D01*
X1122676Y135128D01*
X1122687Y135084D01*
G03X1126075Y132470I3388J889D01*
G03X1127967Y133025I0J3503D01*
G02X1128186Y133024I109J-168D01*
G03X1130125Y132438I1940J2917D01*
G03Y139442I0J3502D01*
G01X1130123D01*
G03X1128233Y138888I0J-3502D01*
G02X1128014Y138889I-109J168D01*
G03X1126075Y139476I-1941J-2915D01*
G03X1124481Y139092I1J-3503D01*
G01X1124480D01*
G02X1124307Y139087I-92J178D01*
G01X1123982Y139234D01*
X1123923Y139302D01*
X1123912Y139346D01*
G03X1123023Y140911I-3388J-889D01*
G02X1122966Y141076I142J141D01*
G01X1123004Y141385D01*
G02X1123096Y141531I199J-23D01*
G03X1124740Y144500I-1859J2969D01*
G03X1121238Y148002I-3502J0D01*
G01X1121236D01*
G03X1120037Y147790I1J-3502D01*
G01X1119991Y147773D01*
X1119894Y147786D01*
X1119585Y148002D01*
G02X1119500Y148166I115J164D01*
G01Y153109D01*
G02X1119564Y153255I200J-1D01*
G01X1119811Y153484D01*
X1119889Y153511D01*
X1119931Y153508D01*
G03X1120200Y153498I265J3492D01*
G03Y160502I0J3502D01*
G03X1117208Y158820I0J-3502D01*
G01Y158819D01*
G02X1117061Y158725I-171J105D01*
G01X1116749Y158688D01*
G02X1116583Y158745I-25J198D01*
G01X1113930Y161398D01*
G02X1113911Y161659I141J141D01*
G03X1114315Y162358I-2810J2091D01*
G02X1114425Y162465I184J-79D01*
G03X1116460Y164637I-1296J3254D01*
G02X1116628Y164774I190J-62D01*
G01X1116990Y164815D01*
G02X1117185Y164717I22J-199D01*
G03X1120199Y162998I3014J1783D01*
G01X1120200D01*
G03Y170002I0J3502D01*
G03X1116869Y167582I0J-3502D01*
G02X1116701Y167445I-190J62D01*
G01X1116339Y167404D01*
G02X1116144Y167502I-22J199D01*
G03X1115525Y168274I-3015J-1783D01*
G02X1115462Y168428I137J146D01*
G01X1115474Y168731D01*
G02X1115549Y168879I200J-8D01*
G03X1116870Y171619I-2181J2740D01*
G03X1113368Y175122I-3503J0D01*
G03X1111140Y174321I1J-3503D01*
G02X1111138Y174319I-142J140D01*
G02X1110999Y174275I-126J156D01*
G01X1110684Y174297D01*
X1110614Y174331D01*
X1110589Y174359D01*
G03X1108001Y175502I-2588J-2359D01*
G01X1108000D01*
G03X1104498Y172000I0J-3502D01*
G01Y171998D01*
G03X1105891Y169203I3502J1D01*
G02X1105968Y169075I-120J-160D01*
G01X1105987Y168956D01*
G02X1105953Y168810I-198J-31D01*
G03X1105318Y166800I2868J-2011D01*
G03X1107492Y163559I3503J0D01*
G02X1107615Y163394I-76J-185D01*
G03X1107636Y163230I3484J363D01*
G01X1107638Y163215D01*
Y163200D01*
G02X1107438Y163000I-200J0D01*
G01X1092118D01*
X1092112D01*
G03X1092000Y163002I-119J-3500D01*
G03X1091888Y163000I7J-3502D01*
G01X1089381D01*
G02X1089229Y163070I0J200D01*
G01X1089003Y163335D01*
X1088979Y163418D01*
X1088986Y163461D01*
G03X1089028Y164000I-3461J541D01*
G03X1088612Y165655I-3503J-1D01*
G02Y165845I176J95D01*
G03X1089028Y167500I-3087J1656D01*
G03X1088612Y169155I-3503J-1D01*
G02Y169345I176J95D01*
G03X1089028Y171000I-3087J1656D01*
G03X1088612Y172655I-3503J-1D01*
G02Y172845I176J95D01*
G03X1089028Y174500I-3087J1656D01*
G03X1082022I-3503J0D01*
G03X1082438Y172845I3503J1D01*
G02Y172655I-176J-95D01*
G03X1082022Y171000I3087J-1656D01*
G03X1082438Y169345I3503J1D01*
G02Y169155I-176J-95D01*
G03X1082022Y167500I3087J-1656D01*
G03X1082438Y165845I3503J1D01*
G02Y165655I-176J-95D01*
G03X1082022Y164000I3087J-1656D01*
G03X1082064Y163461I3503J2D01*
G01X1082071Y163418D01*
X1082047Y163335D01*
X1081821Y163070D01*
G02X1081669Y163000I-152J130D01*
G01X1079911D01*
G02X1079769Y163059I0J200D01*
G01X1072059Y170769D01*
G02X1072000Y170911I141J142D01*
G01Y175194D01*
G02X1072120Y175377I200J0D01*
G03Y181793I-1405J3208D01*
G02X1072000Y181976I80J183D01*
G01Y188032D01*
G02X1072002Y188058I200J-2D01*
G02X1072255Y188224I198J-26D01*
G02X1072270Y188219I-56J-192D01*
G03X1073499Y187996I1230J3281D01*
G01X1073500D01*
G03Y195004I0J3504D01*
G01X1073499D01*
G03X1072270Y194781I1J-3504D01*
G02X1072255Y194776I-71J187D01*
G02X1072002Y194942I-55J192D01*
G02X1072000Y194968I198J28D01*
G01Y198500D01*
G03X1071414Y199914I-1999J0D01*
G01X1066914Y204414D01*
G03X1065500Y205000I-1414J-1413D01*
G01X1018836D01*
G02X1018694Y205059I0J200D01*
G01X1005626Y218127D01*
X1005608Y218259D01*
X1005642Y218318D01*
G03X1008188Y228001I-17142J9683D01*
G03X988502Y247688I-19687J0D01*
G01X907564D01*
G02X907422Y247747I0J200D01*
G01X868059Y287110D01*
G02X868000Y287252I141J142D01*
G01Y287823D01*
X868074Y287926D01*
X868135Y287947D01*
G03Y294573I-1135J3313D01*
G01X868074Y294594D01*
X868000Y294697D01*
Y300965D01*
G02X868091Y301133I200J0D01*
G01X868416Y301343D01*
X868518Y301351D01*
X868564Y301330D01*
G03X870000Y301022I1436J3195D01*
G03X872310Y301892I0J3503D01*
G02X872442Y301942I132J-150D01*
G01X872558D01*
G02X872690Y301892I0J-200D01*
G03X875000Y301022I2310J2633D01*
G03X877310Y301892I0J3503D01*
G02X877442Y301942I132J-150D01*
G01X877558D01*
G02X877690Y301892I0J-200D01*
G03X880000Y301022I2310J2633D01*
G03Y308028I0J3503D01*
G03X877690Y307158I0J-3503D01*
G02X877558Y307108I-132J150D01*
G01X877442D01*
G02X877310Y307158I0J200D01*
G03X875000Y308028I-2310J-2633D01*
G03X872690Y307158I0J-3503D01*
G02X872558Y307108I-132J150D01*
G01X872442D01*
G02X872310Y307158I0J200D01*
G03X870000Y308028I-2310J-2633D01*
G03X868564Y307720I0J-3503D01*
G01X868518Y307699D01*
X868416Y307707D01*
X868091Y307917D01*
G02X868000Y308085I109J168D01*
G01Y309228D01*
G02X868091Y309396I200J0D01*
G01X868416Y309606D01*
X868518Y309614D01*
X868564Y309593D01*
G03X869996Y309286I1434J3195D01*
G01X870000D01*
G03Y316290I0J3502D01*
G01X869996D01*
G03X868564Y315983I2J-3502D01*
G01X868518Y315962D01*
X868416Y315970D01*
X868091Y316180D01*
G02X868000Y316348I109J168D01*
G01Y356644D01*
G02X868070Y356796I200J0D01*
G01X868335Y357022D01*
X868418Y357046D01*
X868461Y357039D01*
G03X869000Y356998I534J3461D01*
G03X870294Y357245I2J3502D01*
G01X870329Y357259D01*
X870407D01*
X870699Y357141D01*
G02X870806Y357038I-75J-185D01*
G03X874000Y354972I3194J1436D01*
G03X875892Y355528I-2J3503D01*
G02X876108I108J-169D01*
G03X878000Y354972I1894J2947D01*
G03X880323Y355853I0J3503D01*
G02X880454Y355904I133J-149D01*
G01X880571D01*
G02X880704Y355855I2J-200D01*
G03X882133Y355106I2297J2644D01*
G01X882177Y355095D01*
X882248Y355036D01*
X882394Y354710D01*
G02X882389Y354535I-182J-82D01*
G03X881998Y352929I3111J-1608D01*
G01Y352925D01*
G03X889002I3502J0D01*
G03X886367Y356319I-3503J0D01*
G01X886323Y356330D01*
X886252Y356389D01*
X886106Y356715D01*
G02X886111Y356890I182J82D01*
G03X886502Y358496I-3111J1608D01*
G01Y358500D01*
G03X883000Y362002I-3502J0D01*
G01X882998D01*
G03X880677Y361122I1J-3502D01*
G02X880546Y361071I-133J149D01*
G01X880429D01*
G02X880296Y361120I-2J200D01*
G03X878000Y361978I-2297J-2645D01*
G03X876108Y361422I2J-3503D01*
G02X875892I-108J169D01*
G03X874000Y361978I-1894J-2947D01*
G03X872706Y361730I1J-3503D01*
G01X872671Y361716D01*
X872593D01*
X872301Y361834D01*
G02X872194Y361937I75J185D01*
G03X871240Y363192I-3194J-1438D01*
G01X871209Y363218D01*
X871173Y363287D01*
X871144Y363610D01*
G02X871189Y363756I199J19D01*
G03X871193Y363760I-2464J2468D01*
G01X871221Y363794D01*
X871301Y363832D01*
X871699D01*
X871779Y363794D01*
X871807Y363760D01*
G03X874500Y362498I2692J2240D01*
G03X875919Y362798I1J3502D01*
G02X876081I81J-183D01*
G03X877500Y362498I1418J3202D01*
G03X880417Y364061I1J3502D01*
G01X880445Y364102D01*
X880533Y364150D01*
X880967D01*
X881055Y364102D01*
X881083Y364061D01*
G03X884000Y362498I2916J1939D01*
G03X885419Y362798I1J3502D01*
G02X885581I81J-183D01*
G03X887000Y362498I1418J3202D01*
G03X889917Y364061I1J3502D01*
G01X889945Y364102D01*
X890033Y364150D01*
X890467D01*
X890555Y364102D01*
X890583Y364061D01*
G03X893500Y362498I2916J1939D01*
G03X894919Y362798I1J3502D01*
G02X895081I81J-183D01*
G03X896500Y362498I1418J3202D01*
G03X899417Y364061I1J3502D01*
G01X899445Y364102D01*
X899533Y364150D01*
X899967D01*
X900055Y364102D01*
X900083Y364061D01*
G03X903000Y362498I2916J1939D01*
G03X904419Y362798I1J3502D01*
G02X904581I81J-183D01*
G03X906000Y362498I1418J3202D01*
G03X907160Y362695I2J3502D01*
G01X907215Y362715D01*
X907326Y362690D01*
X907623Y362397D01*
G02X907672Y362191I-141J-142D01*
G01Y362190D01*
G03X907490Y361076I3320J-1114D01*
G01Y361075D01*
G03X914494I3502J0D01*
G01Y361078D01*
G03X914353Y362060I-3502J-2D01*
G01Y362061D01*
G02X914397Y362252I192J56D01*
G01X914664Y362543D01*
X914764Y362575D01*
X914815Y362565D01*
G03X915500Y362498I682J3435D01*
G03X918417Y364061I1J3502D01*
G01X918445Y364102D01*
X918533Y364150D01*
X918967D01*
X919055Y364102D01*
X919083Y364061D01*
G03X922000Y362498I2916J1939D01*
G03X923419Y362798I1J3502D01*
G02X923581I81J-183D01*
G03X923612Y362784I1457J3185D01*
G02X923718Y362676I-79J-184D01*
G01X923764Y362564D01*
G02X923763Y362413I-186J-74D01*
G03X923498Y361076I3237J-1336D01*
G01Y361075D01*
G03X923831Y359585I3503J1D01*
G02Y359415I-181J-85D01*
G03X923498Y357925I3170J-1491D01*
G01Y357901D01*
G02X923363Y357710I-200J-2D01*
G01X923004Y357587D01*
G02X922780Y357654I-65J189D01*
G01Y357655D01*
G03X920000Y359028I-2781J-2130D01*
G03X917812Y358260I0J-3501D01*
G02X917610Y358232I-125J157D01*
G03X916264Y358502I-1348J-3232D01*
G01X916260D01*
G03Y351498I0J-3502D01*
G01X916262D01*
G03X918448Y352265I-1J3502D01*
G02X918650Y352293I125J-157D01*
G03X920000Y352022I1351J3232D01*
G03X923502Y355525I0J3502D01*
G01Y355549D01*
G02X923637Y355740I200J2D01*
G01X923996Y355863D01*
G02X924220Y355796I65J-189D01*
G01Y355795D01*
G03X927000Y354422I2781J2130D01*
G03X930502Y357923I0J3502D01*
G01Y357925D01*
G03X930169Y359415I-3503J-1D01*
G02Y359585I181J85D01*
G03X930502Y361075I-3170J1491D01*
G01Y361076D01*
G03X930361Y362059I-3502J-1D01*
G01X930346Y362110D01*
X930370Y362211D01*
X930637Y362503D01*
G02X930822Y362564I147J-135D01*
G01X930823D01*
G03X931500Y362498I677J3436D01*
G37*
G36*
G01X876904Y473270D02*
X873874Y470240D01*
G02X873732Y470181I-142J141D01*
G01X699891D01*
G02X699697Y470331I0J200D01*
G01X699601Y470706D01*
G02X699698Y470932I194J51D01*
G01X699699D01*
G03X703414Y477204I-3437J6272D01*
G03X689108I-7153J0D01*
G03X692823Y470932I7152J0D01*
G01X692824D01*
G02X692921Y470706I-97J-175D01*
G01X692825Y470331D01*
G02X692631Y470181I-194J50D01*
G01X669891D01*
G02X669697Y470331I0J200D01*
G01X669601Y470706D01*
G02X669698Y470932I194J51D01*
G01X669699D01*
G03X673414Y477204I-3437J6272D01*
G03X659108I-7153J0D01*
G03X662823Y470932I7152J0D01*
G01X662824D01*
G02X662921Y470706I-97J-175D01*
G01X662825Y470331D01*
G02X662631Y470181I-194J50D01*
G01X542410D01*
G02X542216Y470331I0J200D01*
G01X542120Y470706D01*
G02X542217Y470932I194J51D01*
G01X542218D01*
G03X545932Y477204I-3439J6272D01*
G03X531628I-7152J0D01*
G03X535342Y470932I7153J0D01*
G01X535343D01*
G02X535440Y470706I-97J-175D01*
G01X535344Y470331D01*
G02X535150Y470181I-194J50D01*
G01X512410D01*
G02X512216Y470331I0J200D01*
G01X512120Y470706D01*
G02X512217Y470932I194J51D01*
G01X512218D01*
G03X515932Y477204I-3439J6272D01*
G03X501628I-7152J0D01*
G03X505342Y470932I7153J0D01*
G01X505343D01*
G02X505440Y470706I-97J-175D01*
G01X505344Y470331D01*
G02X505150Y470181I-194J50D01*
G01X384929D01*
G02X384735Y470331I0J200D01*
G01X384639Y470706D01*
G02X384736Y470932I194J51D01*
G01X384737D01*
G03X388452Y477204I-3437J6272D01*
G03X374146I-7153J0D01*
G03X377861Y470932I7152J0D01*
G01X377862D01*
G02X377959Y470706I-97J-175D01*
G01X377863Y470331D01*
G02X377669Y470181I-194J50D01*
G01X354929D01*
G02X354735Y470331I0J200D01*
G01X354639Y470706D01*
G02X354736Y470932I194J51D01*
G01X354737D01*
G03X358452Y477204I-3437J6272D01*
G03X344146I-7153J0D01*
G03X347861Y470932I7152J0D01*
G01X347862D01*
G02X347959Y470706I-97J-175D01*
G01X347863Y470331D01*
G02X347669Y470181I-194J50D01*
G01X227449D01*
G02X227255Y470331I0J200D01*
G01X227159Y470706D01*
G02X227256Y470932I194J51D01*
G01X227257D01*
G03X230972Y477204I-3437J6272D01*
G03X216666I-7153J0D01*
G03X220381Y470932I7152J0D01*
G01X220382D01*
G02X220479Y470706I-97J-175D01*
G01X220383Y470331D01*
G02X220189Y470181I-194J50D01*
G01X197449D01*
G02X197255Y470331I0J200D01*
G01X197159Y470706D01*
G02X197256Y470932I194J51D01*
G01X197257D01*
G03X200972Y477204I-3437J6272D01*
G03X186666I-7153J0D01*
G03X190381Y470932I7152J0D01*
G01X190382D01*
G02X190479Y470706I-97J-175D01*
G01X190383Y470331D01*
G02X190189Y470181I-194J50D01*
G01X162730D01*
G02X162588Y470240I0J200D01*
G01X157559Y475269D01*
G02X157500Y475411I141J142D01*
G01Y570325D01*
G02X157559Y570467I200J0D01*
G01X161773Y574681D01*
G02X161915Y574740I142J-141D01*
G01X873056D01*
G02X873198Y574681I0J-200D01*
G01X876904Y570975D01*
G02X876963Y570833I-141J-142D01*
G01Y568041D01*
G02X876779Y567841I-200J-1D01*
G03Y549399I731J-9221D01*
G02X876963Y549199I-16J-199D01*
G01Y473412D01*
G02X876904Y473270I-200J0D01*
G37*
G36*
G01X1283465Y654614D02*
G02X1289339Y648740I0J-5874D01*
G01Y594488D01*
G02X1283465Y588614I-5874J0D01*
G01X607874D01*
G02X602000Y594488I0J5874D01*
G01Y648740D01*
G02X607874Y654614I5874J0D01*
G01X1283465D01*
G37*
G36*
G01X1261706Y574740D02*
X1271654D01*
G02X1277907Y573440I1J-15685D01*
G02X1278016Y573321I-80J-183D01*
G03X1279438Y572304I1422J486D01*
G03X1279840Y572359I-1J1502D01*
G02X1280000Y572335I53J-193D01*
G02X1286280Y564721I-8346J-13280D01*
G02X1286272Y564560I-187J-71D01*
G03X1286114Y563889I1344J-671D01*
G03X1286870Y562585I1503J0D01*
G02X1286966Y562455I-99J-174D01*
G02X1287339Y559055I-15312J-3400D01*
G01Y552177D01*
G02X1287279Y552034I-200J0D01*
G03Y549890I1052J-1072D01*
G02X1287339Y549747I-140J-143D01*
G01Y532177D01*
G02X1287279Y532034I-200J0D01*
G03Y529890I1052J-1072D01*
G02X1287339Y529747I-140J-143D01*
G01Y512177D01*
G02X1287279Y512034I-200J0D01*
G03Y509890I1052J-1072D01*
G02X1287339Y509747I-140J-143D01*
G01Y492177D01*
G02X1287279Y492034I-200J0D01*
G03Y489890I1052J-1072D01*
G02X1287339Y489747I-140J-143D01*
G01Y472177D01*
G02X1287279Y472034I-200J0D01*
G03Y469890I1052J-1072D01*
G02X1287339Y469747I-140J-143D01*
G01Y452177D01*
G02X1287279Y452034I-200J0D01*
G03Y449890I1052J-1072D01*
G02X1287339Y449747I-140J-143D01*
G01Y432177D01*
G02X1287279Y432034I-200J0D01*
G03Y429890I1052J-1072D01*
G02X1287339Y429747I-140J-143D01*
G01Y412177D01*
G02X1287279Y412034I-200J0D01*
G03Y409890I1052J-1072D01*
G02X1287339Y409747I-140J-143D01*
G01Y392177D01*
G02X1287279Y392034I-200J0D01*
G03Y389890I1052J-1072D01*
G02X1287339Y389747I-140J-143D01*
G01Y372177D01*
G02X1287279Y372034I-200J0D01*
G03Y369890I1052J-1072D01*
G02X1287339Y369747I-140J-143D01*
G01Y352177D01*
G02X1287279Y352034I-200J0D01*
G03Y349890I1052J-1072D01*
G02X1287339Y349747I-140J-143D01*
G01Y332177D01*
G02X1287279Y332034I-200J0D01*
G03Y329890I1052J-1072D01*
G02X1287339Y329747I-140J-143D01*
G01Y312177D01*
G02X1287279Y312034I-200J0D01*
G03Y309890I1052J-1072D01*
G02X1287339Y309747I-140J-143D01*
G01Y292177D01*
G02X1287279Y292034I-200J0D01*
G03Y289890I1052J-1072D01*
G02X1287339Y289747I-140J-143D01*
G01Y272177D01*
G02X1287279Y272034I-200J0D01*
G03Y269890I1052J-1072D01*
G02X1287339Y269747I-140J-143D01*
G01Y252177D01*
G02X1287279Y252034I-200J0D01*
G03Y249890I1052J-1072D01*
G02X1287339Y249747I-140J-143D01*
G01Y232177D01*
G02X1287279Y232034I-200J0D01*
G03Y229890I1052J-1072D01*
G02X1287339Y229747I-140J-143D01*
G01Y212177D01*
G02X1287279Y212034I-200J0D01*
G03Y209890I1052J-1072D01*
G02X1287339Y209747I-140J-143D01*
G01Y192177D01*
G02X1287279Y192034I-200J0D01*
G03Y189890I1052J-1072D01*
G02X1287339Y189747I-140J-143D01*
G01Y172177D01*
G02X1287279Y172034I-200J0D01*
G03Y169890I1052J-1072D01*
G02X1287339Y169747I-140J-143D01*
G01Y152177D01*
G02X1287279Y152034I-200J0D01*
G03Y149890I1052J-1072D01*
G02X1287339Y149747I-140J-143D01*
G01Y132177D01*
G02X1287279Y132034I-200J0D01*
G03Y129890I1052J-1072D01*
G02X1287339Y129747I-140J-143D01*
G01Y112177D01*
G02X1287279Y112034I-200J0D01*
G03Y109890I1052J-1072D01*
G02X1287339Y109747I-140J-143D01*
G01Y92177D01*
G02X1287279Y92034I-200J0D01*
G03Y89890I1052J-1072D01*
G02X1287339Y89747I-140J-143D01*
G01Y72177D01*
G02X1287279Y72034I-200J0D01*
G03Y69890I1052J-1072D01*
G02X1287339Y69747I-140J-143D01*
G01Y52177D01*
G02X1287279Y52034I-200J0D01*
G03Y49890I1052J-1072D01*
G02X1287339Y49747I-140J-143D01*
G01Y32177D01*
G02X1287279Y32034I-200J0D01*
G03Y29890I1052J-1072D01*
G02X1287339Y29747I-140J-143D01*
G01Y19685D01*
G02X1286329Y14147I-15685J-1D01*
G02X1286215Y14031I-187J70D01*
G03X1285264Y12634I551J-1397D01*
G03X1285341Y12159I1502J0D01*
G02X1285326Y11997I-190J-64D01*
G02X1278392Y5521I-13672J7688D01*
G02X1278230Y5517I-86J181D01*
G03X1277657Y5630I-572J-1389D01*
G03X1276300Y4772I0J-1502D01*
G02X1276177Y4666I-181J86D01*
G02X1271654Y4000I-4522J15019D01*
G01X1255793D01*
G02X1255651Y4059I0J200D01*
G03X1253513I-1069J-1055D01*
G02X1253371Y4000I-142J141D01*
G01X1235793D01*
G02X1235651Y4059I0J200D01*
G03X1233513I-1069J-1055D01*
G02X1233371Y4000I-142J141D01*
G01X1215793D01*
G02X1215651Y4059I0J200D01*
G03X1213513I-1069J-1055D01*
G02X1213371Y4000I-142J141D01*
G01X1195793D01*
G02X1195651Y4059I0J200D01*
G03X1193513I-1069J-1055D01*
G02X1193371Y4000I-142J141D01*
G01X1175793D01*
G02X1175651Y4059I0J200D01*
G03X1173513I-1069J-1055D01*
G02X1173371Y4000I-142J141D01*
G01X1155793D01*
G02X1155651Y4059I0J200D01*
G03X1153513I-1069J-1055D01*
G02X1153371Y4000I-142J141D01*
G01X1135793D01*
G02X1135651Y4059I0J200D01*
G03X1133513I-1069J-1055D01*
G02X1133371Y4000I-142J141D01*
G01X1115793D01*
G02X1115651Y4059I0J200D01*
G03X1113513I-1069J-1055D01*
G02X1113371Y4000I-142J141D01*
G01X1095793D01*
G02X1095651Y4059I0J200D01*
G03X1093513I-1069J-1055D01*
G02X1093371Y4000I-142J141D01*
G01X1080911D01*
G02X1080769Y4059I0J200D01*
G01X1078059Y6769D01*
G02X1078000Y6911I141J142D01*
G01Y80000D01*
G03X1077414Y81414I-1999J0D01*
G01X1071914Y86914D01*
G03X1070500Y87500I-1414J-1413D01*
G01X852011D01*
G02X851869Y87559I0J200D01*
G01X848659Y90769D01*
G02X848600Y90911I141J142D01*
G01Y150589D01*
G02X848659Y150731I200J0D01*
G01X850869Y152941D01*
G02X851011Y153000I142J-141D01*
G01X942189D01*
G02X942331Y152941I0J-200D01*
G01X970686Y124586D01*
G03X972100Y124000I1414J1413D01*
G01X1059100D01*
G03X1060514Y124586I0J1999D01*
G01X1065369Y129441D01*
G02X1065511Y129500I142J-141D01*
G01X1080802D01*
X1080910Y129416D01*
X1080927Y129348D01*
G03X1087723I3398J848D01*
G01X1087740Y129416D01*
X1087848Y129500D01*
X1111689D01*
G02X1111831Y129441I0J-200D01*
G01X1112763Y128509D01*
X1112781Y128376D01*
X1112748Y128317D01*
G03X1112298Y126600I3051J-1717D01*
G03X1115327Y123130I3502J0D01*
G01X1115402Y123120D01*
X1115500Y123008D01*
Y118500D01*
G03X1116086Y117086I1999J0D01*
G01X1118086Y115086D01*
G03X1119500Y114500I1414J1413D01*
G01X1138964D01*
G03X1140378Y115086I0J1999D01*
G01X1141914Y116622D01*
G03X1142500Y118036I-1413J1414D01*
G01Y119293D01*
G02X1142559Y119435I200J0D01*
G03Y121565I-1059J1065D01*
G02X1142500Y121707I141J142D01*
G01Y123218D01*
G02X1142559Y123360I200J0D01*
G03Y125490I-1059J1065D01*
G02X1142500Y125632I141J142D01*
G01Y133368D01*
G02X1142559Y133510I200J0D01*
G03Y135640I-1059J1065D01*
G02X1142500Y135782I141J142D01*
G01Y157089D01*
G02X1142559Y157231I200J0D01*
G01X1144269Y158941D01*
G02X1144411Y159000I142J-141D01*
G01X1160500D01*
G03X1161914Y159586I0J1999D01*
G01X1167114Y164786D01*
G03X1167700Y166200I-1413J1414D01*
G01Y176810D01*
G02X1167884Y177010I200J0D01*
G03X1171102Y180500I-283J3490D01*
G03X1170547Y182392I-3502J0D01*
G02Y182608I168J108D01*
G03X1171102Y184500I-2947J1892D01*
G03X1170197Y186850I-3502J1D01*
G01X1170168Y186881D01*
X1170142Y186961D01*
X1170178Y187339D01*
X1170219Y187412D01*
X1170253Y187438D01*
G03X1170452Y187837I-301J399D01*
G01Y198772D01*
G03X1169952Y199272I-500J0D01*
G01X1165171D01*
G03X1164671Y198772I0J-500D01*
G01Y195140D01*
G02X1164596Y194983I-200J-1D01*
G01X1164315Y194759D01*
X1164227Y194739D01*
X1164182Y194750D01*
G03X1163736Y194800I-444J-1950D01*
G01X1135718D01*
G02X1135533Y194925I0J200D01*
G01X1135370Y195325D01*
X1135395Y195444D01*
X1135440Y195487D01*
G03X1136502Y198000I-2440J2512D01*
G03X1133000Y201502I-3502J0D01*
G03X1129680Y199115I0J-3502D01*
G02X1129467Y198980I-190J64D01*
G03X1129068Y199002I-392J-3480D01*
G03X1127496Y198630I-1J-3502D01*
G02X1127325Y198625I-91J178D01*
G03X1125918Y198920I-1407J-3208D01*
G03X1122416Y195418I0J-3502D01*
G03X1122421Y195222I3502J-9D01*
G01X1122423Y195180D01*
X1122396Y195104D01*
X1122167Y194863D01*
G02X1122022Y194800I-146J137D01*
G01X1115611D01*
G02X1115469Y194859I0J200D01*
G01X1097334Y212994D01*
G02X1097275Y213136I141J142D01*
G01Y228491D01*
G02X1097334Y228633I200J0D01*
G01X1101748Y233047D01*
G02X1101890Y233106I142J-141D01*
G01X1175296D01*
G03X1176710Y233692I0J1999D01*
G01X1181585Y238567D01*
G03X1182171Y239981I-1413J1414D01*
G01Y285994D01*
G02X1182230Y286136I200J0D01*
G01X1183835Y287741D01*
G02X1183977Y287800I142J-141D01*
G01X1206500D01*
G03X1207914Y288386I0J1999D01*
G01X1215969Y296441D01*
G02X1216111Y296500I142J-141D01*
G01X1259400D01*
G03X1260814Y297086I0J1999D01*
G01X1264914Y301186D01*
G03X1265500Y302600I-1413J1414D01*
G01Y476000D01*
G03X1264914Y477414I-1999J0D01*
G01X1259814Y482514D01*
G03X1258400Y483100I-1414J-1413D01*
G01X1196911D01*
G02X1196769Y483159I0J200D01*
G01X1182230Y497698D01*
G02X1182171Y497840I141J142D01*
G01Y518623D01*
G03X1181585Y520037I-1999J0D01*
G01X1176743Y524879D01*
G03X1175329Y525465I-1414J-1413D01*
G01X1101564D01*
G02X1101422Y525524I0J200D01*
G01X1097334Y529612D01*
G02X1097275Y529754I141J142D01*
G01Y571956D01*
G02X1097334Y572098I200J0D01*
G01X1099641Y574405D01*
X1099767Y574425D01*
X1099826Y574396D01*
G03X1100498Y574237I673J1343D01*
G03X1101564Y574681I0J1502D01*
G02X1101706Y574740I142J-141D01*
G01X1119290D01*
G02X1119432Y574681I0J-200D01*
G03X1121564I1066J1058D01*
G02X1121706Y574740I142J-141D01*
G01X1139290D01*
G02X1139432Y574681I0J-200D01*
G03X1141564I1066J1058D01*
G02X1141706Y574740I142J-141D01*
G01X1159290D01*
G02X1159432Y574681I0J-200D01*
G03X1161564I1066J1058D01*
G02X1161706Y574740I142J-141D01*
G01X1179290D01*
G02X1179432Y574681I0J-200D01*
G03X1181564I1066J1058D01*
G02X1181706Y574740I142J-141D01*
G01X1199290D01*
G02X1199432Y574681I0J-200D01*
G03X1201564I1066J1058D01*
G02X1201706Y574740I142J-141D01*
G01X1219290D01*
G02X1219432Y574681I0J-200D01*
G03X1221564I1066J1058D01*
G02X1221706Y574740I142J-141D01*
G01X1239290D01*
G02X1239432Y574681I0J-200D01*
G03X1241564I1066J1058D01*
G02X1241706Y574740I142J-141D01*
G01X1259290D01*
G02X1259432Y574681I0J-200D01*
G03X1261564I1066J1058D01*
G02X1261706Y574740I142J-141D01*
G37*
G36*
G01X1102061Y377400D02*
X1173385D01*
G02X1173527Y377341I0J-200D01*
G01X1178112Y372756D01*
G02X1178171Y372614I-141J-142D01*
G01Y338657D01*
G02X1178140Y338551I-200J1D01*
G03X1177909Y337750I1271J-800D01*
G03X1178140Y336949I1502J-1D01*
G02X1178171Y336843I-169J-107D01*
G01Y335157D01*
G02X1178140Y335051I-200J1D01*
G03X1177909Y334250I1271J-800D01*
G03X1178140Y333449I1502J-1D01*
G02X1178171Y333343I-169J-107D01*
G01Y331657D01*
G02X1178140Y331551I-200J1D01*
G03X1177909Y330750I1271J-800D01*
G03X1178140Y329949I1502J-1D01*
G02X1178171Y329843I-169J-107D01*
G01Y328157D01*
G02X1178140Y328051I-200J1D01*
G03X1177909Y327250I1271J-800D01*
G03X1178140Y326449I1502J-1D01*
G02X1178171Y326343I-169J-107D01*
G01Y310199D01*
X1178168Y310183D01*
G03X1178149Y309942I1483J-238D01*
G03X1178168Y309701I1502J-3D01*
G01X1178171Y309685D01*
Y306199D01*
X1178168Y306183D01*
G03X1178149Y305942I1483J-238D01*
G03X1178168Y305701I1502J-3D01*
G01X1178171Y305685D01*
Y240892D01*
G02X1178112Y240750I-200J0D01*
G01X1174527Y237165D01*
G02X1174385Y237106I-142J141D01*
G01X1101890D01*
G02X1101748Y237165I0J200D01*
G01X1097334Y241579D01*
G02X1097275Y241721I141J142D01*
G01Y372614D01*
G02X1097334Y372756I200J0D01*
G01X1101919Y377341D01*
G02X1102061Y377400I142J-141D01*
G37*
G36*
G01X1101564Y521465D02*
X1174418D01*
G02X1174560Y521406I0J-200D01*
G01X1178112Y517854D01*
G02X1178171Y517712I-141J-142D01*
G01Y480974D01*
X1178161Y480931D01*
X1178151Y480910D01*
G03X1177998Y480250I1349J-660D01*
G03X1178151Y479590I1502J0D01*
G01X1178161Y479569D01*
X1178171Y479526D01*
Y477474D01*
X1178161Y477431D01*
X1178151Y477410D01*
G03X1177998Y476750I1349J-660D01*
G03X1178151Y476090I1502J0D01*
G01X1178161Y476069D01*
X1178171Y476026D01*
Y473974D01*
X1178161Y473931D01*
X1178151Y473910D01*
G03X1177998Y473250I1349J-660D01*
G03X1178151Y472590I1502J0D01*
G01X1178161Y472569D01*
X1178171Y472526D01*
Y470474D01*
X1178161Y470431D01*
X1178151Y470410D01*
G03X1177998Y469750I1349J-660D01*
G03X1178151Y469090I1502J0D01*
G01X1178161Y469069D01*
X1178171Y469026D01*
Y386186D01*
G02X1178112Y386044I-200J0D01*
G01X1173527Y381459D01*
G02X1173385Y381400I-142J141D01*
G01X1102061D01*
G02X1101919Y381459I0J200D01*
G01X1097334Y386044D01*
G02X1097275Y386186I141J142D01*
G01Y517176D01*
G02X1097334Y517318I200J0D01*
G01X1101422Y521406D01*
G02X1101564Y521465I142J-141D01*
G37*
G36*
G01X1205589Y291800D02*
X1183977D01*
G02X1183835Y291859I0J200D01*
G01X1182230Y293464D01*
G02X1182171Y293606I141J142D01*
G01Y348245D01*
G02X1182208Y348361I200J0D01*
G03Y350107I-1222J873D01*
G02X1182171Y350223I163J116D01*
G01Y474987D01*
G02X1182230Y475129I200J0D01*
G01X1186142Y479041D01*
G02X1186284Y479100I142J-141D01*
G01X1257489D01*
G02X1257631Y479041I0J-200D01*
G01X1261441Y475231D01*
G02X1261500Y475089I-141J-142D01*
G01Y303511D01*
G02X1261441Y303369I-200J0D01*
G01X1258631Y300559D01*
G02X1258489Y300500I-142J141D01*
G01X1215200D01*
G03X1213786Y299914I0J-1999D01*
G01X1205731Y291859D01*
G02X1205589Y291800I-142J141D01*
G37*
%LPD*%
G75*
G36*
G01X43781Y349915D02*
G02X48780Y354726I4999J-192D01*
G02X53782Y349724I0J-5002D01*
G02X48971Y344725I-5003J0D01*
G03X48779Y344533I8J-200D01*
G02X43780Y339722I-4999J192D01*
G02X38778Y344724I0J5002D01*
G02X43589Y349723I5003J0D01*
G03X43781Y349915I-8J200D01*
G37*
G36*
G01X301598Y162515D02*
X301906D01*
G03X302075Y162609I-1J200D01*
G02X306752Y165200I4677J-2926D01*
G02X312267Y159685I0J-5515D01*
G02X309676Y155008I-5517J0D01*
G03X309582Y154839I106J-170D01*
G01Y154531D01*
G03X309676Y154362I200J1D01*
G02Y145008I-2925J-4677D01*
G03X309582Y144839I106J-170D01*
G01Y144531D01*
G03X309676Y144362I200J1D01*
G02Y135008I-2925J-4677D01*
G03X309582Y134839I106J-170D01*
G01Y134531D01*
G03X309676Y134362I200J1D01*
G02X312267Y129685I-2926J-4677D01*
G02X306752Y124170I-5515J0D01*
G02X302075Y126761I0J5517D01*
G03X301906Y126855I-170J-106D01*
G01X301598D01*
G03X301429Y126761I1J-200D01*
G02X296752Y124170I-4677J2926D01*
G02X291237Y129685I0J5515D01*
G02X293828Y134362I5517J0D01*
G03X293922Y134531I-106J170D01*
G01Y134839D01*
G03X293828Y135008I-200J-1D01*
G02Y144362I2925J4677D01*
G03X293922Y144531I-106J170D01*
G01Y144839D01*
G03X293828Y145008I-200J-1D01*
G02Y154362I2925J4677D01*
G03X293922Y154531I-106J170D01*
G01Y154839D01*
G03X293828Y155008I-200J-1D01*
G02X291237Y159685I2926J4677D01*
G02X296752Y165200I5515J0D01*
G02X301429Y162609I0J-5517D01*
G03X301598Y162515I170J106D01*
G37*
G36*
G01X336598D02*
X336906D01*
G03X337075Y162609I-1J200D01*
G02X341752Y165200I4677J-2926D01*
G02X347267Y159685I0J-5515D01*
G02X344676Y155008I-5517J0D01*
G03X344582Y154839I106J-170D01*
G01Y154531D01*
G03X344676Y154362I200J1D01*
G02Y145008I-2925J-4677D01*
G03X344582Y144839I106J-170D01*
G01Y144531D01*
G03X344676Y144362I200J1D01*
G02Y135008I-2925J-4677D01*
G03X344582Y134839I106J-170D01*
G01Y134531D01*
G03X344676Y134362I200J1D01*
G02X347267Y129685I-2926J-4677D01*
G02X341752Y124170I-5515J0D01*
G02X337075Y126761I0J5517D01*
G03X336906Y126855I-170J-106D01*
G01X336598D01*
G03X336429Y126761I1J-200D01*
G02X331752Y124170I-4677J2926D01*
G02X326237Y129685I0J5515D01*
G02X328828Y134362I5517J0D01*
G03X328922Y134531I-106J170D01*
G01Y134839D01*
G03X328828Y135008I-200J-1D01*
G02Y144362I2925J4677D01*
G03X328922Y144531I-106J170D01*
G01Y144839D01*
G03X328828Y145008I-200J-1D01*
G02Y154362I2925J4677D01*
G03X328922Y154531I-106J170D01*
G01Y154839D01*
G03X328828Y155008I-200J-1D01*
G02X326237Y159685I2926J4677D01*
G02X331752Y165200I5515J0D01*
G02X336429Y162609I0J-5517D01*
G03X336598Y162515I170J106D01*
G37*
G36*
G01X371598D02*
X371906D01*
G03X372075Y162609I-1J200D01*
G02X376752Y165200I4677J-2926D01*
G02X382267Y159685I0J-5515D01*
G02X379676Y155008I-5517J0D01*
G03X379582Y154839I106J-170D01*
G01Y154531D01*
G03X379676Y154362I200J1D01*
G02Y145008I-2925J-4677D01*
G03X379582Y144839I106J-170D01*
G01Y144531D01*
G03X379676Y144362I200J1D01*
G02Y135008I-2925J-4677D01*
G03X379582Y134839I106J-170D01*
G01Y134531D01*
G03X379676Y134362I200J1D01*
G02X382267Y129685I-2926J-4677D01*
G02X376752Y124170I-5515J0D01*
G02X372075Y126761I0J5517D01*
G03X371906Y126855I-170J-106D01*
G01X371598D01*
G03X371429Y126761I1J-200D01*
G02X366752Y124170I-4677J2926D01*
G02X361237Y129685I0J5515D01*
G02X363828Y134362I5517J0D01*
G03X363922Y134531I-106J170D01*
G01Y134839D01*
G03X363828Y135008I-200J-1D01*
G02Y144362I2925J4677D01*
G03X363922Y144531I-106J170D01*
G01Y144839D01*
G03X363828Y145008I-200J-1D01*
G02Y154362I2925J4677D01*
G03X363922Y154531I-106J170D01*
G01Y154839D01*
G03X363828Y155008I-200J-1D01*
G02X361237Y159685I2926J4677D01*
G02X366752Y165200I5515J0D01*
G02X371429Y162609I0J-5517D01*
G03X371598Y162515I170J106D01*
G37*
G36*
G01X169210Y222261D02*
Y222263D01*
G02X172712Y225765I3502J0D01*
G02X176210Y222440I0J-3503D01*
G03X176386Y222251I200J9D01*
G02X179476Y218775I-410J-3476D01*
G02X175976Y215275I-3500J0D01*
G02X174191Y215764I-1J3500D01*
G03X174027Y215782I-102J-172D01*
G02X172936Y215608I-1090J3328D01*
G01X172934D01*
G02X169432Y219110I0J3502D01*
G01Y219113D01*
G02X169669Y220379I3502J0D01*
G03X169657Y220549I-186J72D01*
G02X169210Y222261I3055J1712D01*
G37*
G36*
G01X600998Y203000D02*
Y203003D01*
G02X601203Y204183I3502J-1D01*
G03Y204317I-188J67D01*
G02X600998Y205497I3297J1181D01*
G01Y205500D01*
G02X608002I3502J0D01*
G01Y205497D01*
G02X607797Y204317I-3502J1D01*
G03Y204183I188J-67D01*
G02X608002Y203003I-3297J-1181D01*
G01Y203000D01*
G02X607133Y200690I-3503J-1D01*
G03X607083Y200559I150J-132D01*
G01Y200441D01*
G03X607133Y200310I200J1D01*
G02X608002Y198000I-2634J-2309D01*
G01Y197997D01*
G02X607797Y196817I-3502J1D01*
G03Y196683I188J-67D01*
G02X608002Y195503I-3297J-1181D01*
G01Y195500D01*
G02X600998I-3502J0D01*
G01Y195503D01*
G02X601203Y196683I3502J-1D01*
G03Y196817I-188J67D01*
G02X600998Y197997I3297J1181D01*
G01Y198000D01*
G02X601867Y200310I3503J1D01*
G03X601917Y200441I-150J132D01*
G01Y200559D01*
G03X601867Y200690I-200J-1D01*
G02X600998Y203000I2634J2309D01*
G37*
G36*
G01X622498D02*
Y203003D01*
G02X622703Y204183I3502J-1D01*
G03Y204317I-188J67D01*
G02X622498Y205497I3297J1181D01*
G01Y205500D01*
G02X629502I3502J0D01*
G01Y205497D01*
G02X629297Y204317I-3502J1D01*
G03Y204183I188J-67D01*
G02X629502Y203003I-3297J-1181D01*
G01Y203000D01*
G02X628633Y200690I-3503J-1D01*
G03X628583Y200559I150J-132D01*
G01Y200441D01*
G03X628633Y200310I200J1D01*
G02X629502Y198000I-2634J-2309D01*
G01Y197997D01*
G02X629297Y196817I-3502J1D01*
G03Y196683I188J-67D01*
G02X629502Y195503I-3297J-1181D01*
G01Y195500D01*
G02X622498I-3502J0D01*
G01Y195503D01*
G02X622703Y196683I3502J-1D01*
G03Y196817I-188J67D01*
G02X622498Y197997I3297J1181D01*
G01Y198000D01*
G02X623367Y200310I3503J1D01*
G03X623417Y200441I-150J132D01*
G01Y200559D01*
G03X623367Y200690I-200J-1D01*
G02X622498Y203000I2634J2309D01*
G37*
G36*
G01X643998D02*
Y203003D01*
G02X644203Y204183I3502J-1D01*
G03Y204317I-188J67D01*
G02X643998Y205497I3297J1181D01*
G01Y205500D01*
G02X651002I3502J0D01*
G01Y205497D01*
G02X650797Y204317I-3502J1D01*
G03Y204183I188J-67D01*
G02X651002Y203003I-3297J-1181D01*
G01Y203000D01*
G02X650133Y200690I-3503J-1D01*
G03X650083Y200559I150J-132D01*
G01Y200441D01*
G03X650133Y200310I200J1D01*
G02X651002Y198000I-2634J-2309D01*
G01Y197997D01*
G02X650797Y196817I-3502J1D01*
G03Y196683I188J-67D01*
G02X651002Y195503I-3297J-1181D01*
G01Y195500D01*
G02X643998I-3502J0D01*
G01Y195503D01*
G02X644203Y196683I3502J-1D01*
G03Y196817I-188J67D01*
G02X643998Y197997I3297J1181D01*
G01Y198000D01*
G02X644867Y200310I3503J1D01*
G03X644917Y200441I-150J132D01*
G01Y200559D01*
G03X644867Y200690I-200J-1D01*
G02X643998Y203000I2634J2309D01*
G37*
G36*
G01X665498D02*
Y203003D01*
G02X665703Y204183I3502J-1D01*
G03Y204317I-188J67D01*
G02X665498Y205497I3297J1181D01*
G01Y205500D01*
G02X672502I3502J0D01*
G01Y205497D01*
G02X672297Y204317I-3502J1D01*
G03Y204183I188J-67D01*
G02X672502Y203003I-3297J-1181D01*
G01Y203000D01*
G02X671633Y200690I-3503J-1D01*
G03X671583Y200559I150J-132D01*
G01Y200441D01*
G03X671633Y200310I200J1D01*
G02X672502Y198000I-2634J-2309D01*
G01Y197997D01*
G02X672297Y196817I-3502J1D01*
G03Y196683I188J-67D01*
G02X672502Y195503I-3297J-1181D01*
G01Y195500D01*
G02X665498I-3502J0D01*
G01Y195503D01*
G02X665703Y196683I3502J-1D01*
G03Y196817I-188J67D01*
G02X665498Y197997I3297J1181D01*
G01Y198000D01*
G02X666367Y200310I3503J1D01*
G03X666417Y200441I-150J132D01*
G01Y200559D01*
G03X666367Y200690I-200J-1D01*
G02X665498Y203000I2634J2309D01*
G37*
G36*
G01X686998D02*
Y203003D01*
G02X687203Y204183I3502J-1D01*
G03Y204317I-188J67D01*
G02X686998Y205497I3297J1181D01*
G01Y205500D01*
G02X694002I3502J0D01*
G01Y205497D01*
G02X693797Y204317I-3502J1D01*
G03Y204183I188J-67D01*
G02X694002Y203003I-3297J-1181D01*
G01Y203000D01*
G02X693133Y200690I-3503J-1D01*
G03X693083Y200559I150J-132D01*
G01Y200441D01*
G03X693133Y200310I200J1D01*
G02X694002Y198000I-2634J-2309D01*
G01Y197997D01*
G02X693797Y196817I-3502J1D01*
G03Y196683I188J-67D01*
G02X694002Y195503I-3297J-1181D01*
G01Y195500D01*
G02X686998I-3502J0D01*
G01Y195503D01*
G02X687203Y196683I3502J-1D01*
G03Y196817I-188J67D01*
G02X686998Y197997I3297J1181D01*
G01Y198000D01*
G02X687867Y200310I3503J1D01*
G03X687917Y200441I-150J132D01*
G01Y200559D01*
G03X687867Y200690I-200J-1D01*
G02X686998Y203000I2634J2309D01*
G37*
G36*
G01X708488D02*
Y203003D01*
G02X708693Y204183I3502J-1D01*
G03Y204317I-188J67D01*
G02X708488Y205497I3297J1181D01*
G01Y205500D01*
G02X715492I3502J0D01*
G01Y205497D01*
G02X715287Y204317I-3502J1D01*
G03Y204183I188J-67D01*
G02X715492Y203003I-3297J-1181D01*
G01Y203000D01*
G02X714623Y200690I-3503J-1D01*
G03X714573Y200559I150J-132D01*
G01Y200441D01*
G03X714623Y200310I200J1D01*
G02X715492Y198000I-2634J-2309D01*
G01Y197997D01*
G02X715287Y196817I-3502J1D01*
G03Y196683I188J-67D01*
G02X715492Y195503I-3297J-1181D01*
G01Y195500D01*
G02X708488I-3502J0D01*
G01Y195503D01*
G02X708693Y196683I3502J-1D01*
G03Y196817I-188J67D01*
G02X708488Y197997I3297J1181D01*
G01Y198000D01*
G02X709357Y200310I3503J1D01*
G03X709407Y200441I-150J132D01*
G01Y200559D01*
G03X709357Y200690I-200J-1D01*
G02X708488Y203000I2634J2309D01*
G37*
G36*
G01X729988D02*
Y203003D01*
G02X730193Y204183I3502J-1D01*
G03Y204317I-188J67D01*
G02X729988Y205497I3297J1181D01*
G01Y205500D01*
G02X736992I3502J0D01*
G01Y205497D01*
G02X736787Y204317I-3502J1D01*
G03Y204183I188J-67D01*
G02X736992Y203003I-3297J-1181D01*
G01Y203000D01*
G02X736123Y200690I-3503J-1D01*
G03X736073Y200559I150J-132D01*
G01Y200441D01*
G03X736123Y200310I200J1D01*
G02X736992Y198000I-2634J-2309D01*
G01Y197997D01*
G02X736787Y196817I-3502J1D01*
G03Y196683I188J-67D01*
G02X736992Y195503I-3297J-1181D01*
G01Y195500D01*
G02X729988I-3502J0D01*
G01Y195503D01*
G02X730193Y196683I3502J-1D01*
G03Y196817I-188J67D01*
G02X729988Y197997I3297J1181D01*
G01Y198000D01*
G02X730857Y200310I3503J1D01*
G03X730907Y200441I-150J132D01*
G01Y200559D01*
G03X730857Y200690I-200J-1D01*
G02X729988Y203000I2634J2309D01*
G37*
G36*
G01X293498Y203500D02*
Y203503D01*
G02X293703Y204683I3502J-1D01*
G03Y204817I-188J67D01*
G02X293498Y205997I3297J1181D01*
G01Y206000D01*
G02X300502I3502J0D01*
G01Y205997D01*
G02X300297Y204817I-3502J1D01*
G03Y204683I188J-67D01*
G02X300502Y203503I-3297J-1181D01*
G01Y203500D01*
G02X299633Y201190I-3503J-1D01*
G03X299583Y201059I150J-132D01*
G01Y200941D01*
G03X299633Y200810I200J1D01*
G02X300502Y198500I-2634J-2309D01*
G01Y198497D01*
G02X300297Y197317I-3502J1D01*
G03Y197183I188J-67D01*
G02X300502Y196003I-3297J-1181D01*
G01Y196000D01*
G02X293498I-3502J0D01*
G01Y196003D01*
G02X293703Y197183I3502J-1D01*
G03Y197317I-188J67D01*
G02X293498Y198497I3297J1181D01*
G01Y198500D01*
G02X294367Y200810I3503J1D01*
G03X294417Y200941I-150J132D01*
G01Y201059D01*
G03X294367Y201190I-200J-1D01*
G02X293498Y203500I2634J2309D01*
G37*
G36*
G01X314998D02*
Y203503D01*
G02X315203Y204683I3502J-1D01*
G03Y204817I-188J67D01*
G02X314998Y205997I3297J1181D01*
G01Y206000D01*
G02X322002I3502J0D01*
G01Y205997D01*
G02X321797Y204817I-3502J1D01*
G03Y204683I188J-67D01*
G02X322002Y203503I-3297J-1181D01*
G01Y203500D01*
G02X321133Y201190I-3503J-1D01*
G03X321083Y201059I150J-132D01*
G01Y200941D01*
G03X321133Y200810I200J1D01*
G02X322002Y198500I-2634J-2309D01*
G01Y198497D01*
G02X321797Y197317I-3502J1D01*
G03Y197183I188J-67D01*
G02X322002Y196003I-3297J-1181D01*
G01Y196000D01*
G02X314998I-3502J0D01*
G01Y196003D01*
G02X315203Y197183I3502J-1D01*
G03Y197317I-188J67D01*
G02X314998Y198497I3297J1181D01*
G01Y198500D01*
G02X315867Y200810I3503J1D01*
G03X315917Y200941I-150J132D01*
G01Y201059D01*
G03X315867Y201190I-200J-1D01*
G02X314998Y203500I2634J2309D01*
G37*
G36*
G01X336498D02*
Y203503D01*
G02X336703Y204683I3502J-1D01*
G03Y204817I-188J67D01*
G02X336498Y205997I3297J1181D01*
G01Y206000D01*
G02X343502I3502J0D01*
G01Y205997D01*
G02X343297Y204817I-3502J1D01*
G03Y204683I188J-67D01*
G02X343502Y203503I-3297J-1181D01*
G01Y203500D01*
G02X342633Y201190I-3503J-1D01*
G03X342583Y201059I150J-132D01*
G01Y200941D01*
G03X342633Y200810I200J1D01*
G02X343502Y198500I-2634J-2309D01*
G01Y198497D01*
G02X343297Y197317I-3502J1D01*
G03Y197183I188J-67D01*
G02X343502Y196003I-3297J-1181D01*
G01Y196000D01*
G02X336498I-3502J0D01*
G01Y196003D01*
G02X336703Y197183I3502J-1D01*
G03Y197317I-188J67D01*
G02X336498Y198497I3297J1181D01*
G01Y198500D01*
G02X337367Y200810I3503J1D01*
G03X337417Y200941I-150J132D01*
G01Y201059D01*
G03X337367Y201190I-200J-1D01*
G02X336498Y203500I2634J2309D01*
G37*
G36*
G01X357998D02*
Y203503D01*
G02X358203Y204683I3502J-1D01*
G03Y204817I-188J67D01*
G02X357998Y205997I3297J1181D01*
G01Y206000D01*
G02X365002I3502J0D01*
G01Y205997D01*
G02X364797Y204817I-3502J1D01*
G03Y204683I188J-67D01*
G02X365002Y203503I-3297J-1181D01*
G01Y203500D01*
G02X364133Y201190I-3503J-1D01*
G03X364083Y201059I150J-132D01*
G01Y200941D01*
G03X364133Y200810I200J1D01*
G02X365002Y198500I-2634J-2309D01*
G01Y198497D01*
G02X364797Y197317I-3502J1D01*
G03Y197183I188J-67D01*
G02X365002Y196003I-3297J-1181D01*
G01Y196000D01*
G02X357998I-3502J0D01*
G01Y196003D01*
G02X358203Y197183I3502J-1D01*
G03Y197317I-188J67D01*
G02X357998Y198497I3297J1181D01*
G01Y198500D01*
G02X358867Y200810I3503J1D01*
G03X358917Y200941I-150J132D01*
G01Y201059D01*
G03X358867Y201190I-200J-1D01*
G02X357998Y203500I2634J2309D01*
G37*
G36*
G01X379498D02*
Y203503D01*
G02X379703Y204683I3502J-1D01*
G03Y204817I-188J67D01*
G02X379498Y205997I3297J1181D01*
G01Y206000D01*
G02X386502I3502J0D01*
G01Y205997D01*
G02X386297Y204817I-3502J1D01*
G03Y204683I188J-67D01*
G02X386502Y203503I-3297J-1181D01*
G01Y203500D01*
G02X385633Y201190I-3503J-1D01*
G03X385583Y201059I150J-132D01*
G01Y200941D01*
G03X385633Y200810I200J1D01*
G02X386502Y198500I-2634J-2309D01*
G01Y198497D01*
G02X386297Y197317I-3502J1D01*
G03Y197183I188J-67D01*
G02X386502Y196003I-3297J-1181D01*
G01Y196000D01*
G02X379498I-3502J0D01*
G01Y196003D01*
G02X379703Y197183I3502J-1D01*
G03Y197317I-188J67D01*
G02X379498Y198497I3297J1181D01*
G01Y198500D01*
G02X380367Y200810I3503J1D01*
G03X380417Y200941I-150J132D01*
G01Y201059D01*
G03X380367Y201190I-200J-1D01*
G02X379498Y203500I2634J2309D01*
G37*
G36*
G01X400998D02*
Y203503D01*
G02X401203Y204683I3502J-1D01*
G03Y204817I-188J67D01*
G02X400998Y205997I3297J1181D01*
G01Y206000D01*
G02X408002I3502J0D01*
G01Y205997D01*
G02X407797Y204817I-3502J1D01*
G03Y204683I188J-67D01*
G02X408002Y203503I-3297J-1181D01*
G01Y203500D01*
G02X407133Y201190I-3503J-1D01*
G03X407083Y201059I150J-132D01*
G01Y200941D01*
G03X407133Y200810I200J1D01*
G02X408002Y198500I-2634J-2309D01*
G01Y198497D01*
G02X407797Y197317I-3502J1D01*
G03Y197183I188J-67D01*
G02X408002Y196003I-3297J-1181D01*
G01Y196000D01*
G02X400998I-3502J0D01*
G01Y196003D01*
G02X401203Y197183I3502J-1D01*
G03Y197317I-188J67D01*
G02X400998Y198497I3297J1181D01*
G01Y198500D01*
G02X401867Y200810I3503J1D01*
G03X401917Y200941I-150J132D01*
G01Y201059D01*
G03X401867Y201190I-200J-1D01*
G02X400998Y203500I2634J2309D01*
G37*
G36*
G01X422498D02*
Y203503D01*
G02X422703Y204683I3502J-1D01*
G03Y204817I-188J67D01*
G02X422498Y205997I3297J1181D01*
G01Y206000D01*
G02X429502I3502J0D01*
G01Y205997D01*
G02X429297Y204817I-3502J1D01*
G03Y204683I188J-67D01*
G02X429502Y203503I-3297J-1181D01*
G01Y203500D01*
G02X428633Y201190I-3503J-1D01*
G03X428583Y201059I150J-132D01*
G01Y200941D01*
G03X428633Y200810I200J1D01*
G02X429502Y198500I-2634J-2309D01*
G01Y198497D01*
G02X429297Y197317I-3502J1D01*
G03Y197183I188J-67D01*
G02X429502Y196003I-3297J-1181D01*
G01Y196000D01*
G02X422498I-3502J0D01*
G01Y196003D01*
G02X422703Y197183I3502J-1D01*
G03Y197317I-188J67D01*
G02X422498Y198497I3297J1181D01*
G01Y198500D01*
G02X423367Y200810I3503J1D01*
G03X423417Y200941I-150J132D01*
G01Y201059D01*
G03X423367Y201190I-200J-1D01*
G02X422498Y203500I2634J2309D01*
G37*
G36*
G01X148832Y226563D02*
G02X149247Y228219I3502J2D01*
G03Y228407I-176J94D01*
G02X148832Y230061I3087J1654D01*
G01Y230063D01*
G02X152065Y233555I3502J0D01*
G03X152211Y233636I-15J200D01*
G02X155034Y235066I2823J-2071D01*
G02X158536Y231563I-1J-3503D01*
G01Y231561D01*
G02X158121Y229907I-3502J0D01*
G03Y229719I176J-94D01*
G02X158536Y228063I-3087J-1654D01*
G02X158121Y226407I-3502J-2D01*
G03Y226219I176J-94D01*
G02X158536Y224565I-3087J-1654D01*
G01Y224563D01*
G02X155303Y221071I-3502J0D01*
G03X155157Y220990I15J-200D01*
G02X154140Y220062I-2823J2073D01*
G03X154048Y219846I103J-171D01*
G02X154136Y219063I-3414J-780D01*
G02X153716Y217398I-3502J-2D01*
G01X153692Y217355D01*
X153691Y217258D01*
X153880Y216877D01*
X153959Y216820D01*
X154007Y216813D01*
G02X156982Y213350I-528J-3463D01*
G02X149978I-3502J0D01*
G01Y213354D01*
G02X150398Y215015I3502J-2D01*
G01X150422Y215058D01*
X150423Y215155D01*
X150234Y215536D01*
X150155Y215593D01*
X150107Y215600D01*
G02X147132Y219063I528J3463D01*
G02X148828Y222064I3503J0D01*
G03X148920Y222280I-103J171D01*
G02X148832Y223063I3414J780D01*
G02X149247Y224719I3502J2D01*
G03Y224907I-176J94D01*
G02X148832Y226563I3087J1654D01*
G37*
G36*
G01X195760Y248602D02*
G02X197179Y248302I1J-3502D01*
G03X197341I81J183D01*
G02X198760Y248602I1418J-3202D01*
G02X200179Y248302I1J-3502D01*
G03X200341I81J183D01*
G02X201758Y248602I1418J-3202D01*
G01X201760D01*
G02X205262Y245100I0J-3502D01*
G01Y245098D01*
G02X204962Y243681I-3502J1D01*
G03Y243519I183J-81D01*
G02X205262Y242102I-3202J-1418D01*
G01Y242100D01*
G02X201760Y238598I-3502J0D01*
G01X201758D01*
G02X200341Y238898I1J3502D01*
G03X200179I-81J-183D01*
G02X198760Y238598I-1418J3202D01*
G02X197341Y238898I-1J3502D01*
G03X197179I-81J-183D01*
G02X195760Y238598I-1418J3202D01*
G02X194341Y238898I-1J3502D01*
G03X194179I-81J-183D01*
G02X192760Y238598I-1418J3202D01*
G02X191341Y238898I-1J3502D01*
G03X191179I-81J-183D01*
G02X189762Y238598I-1418J3202D01*
G01X189760D01*
G02X186258Y242100I0J3502D01*
G01Y242102D01*
G02X186558Y243519I3502J-1D01*
G03Y243681I-183J81D01*
G02X186258Y245098I3202J1418D01*
G01Y245100D01*
G02X189760Y248602I3502J0D01*
G01X189762D01*
G02X191179Y248302I-1J-3502D01*
G03X191341I81J183D01*
G02X192760Y248602I1418J-3202D01*
G02X194179Y248302I1J-3502D01*
G03X194341I81J183D01*
G02X195760Y248602I1418J-3202D01*
G37*
G36*
G01X394998Y242500D02*
Y242501D01*
G02X395719Y244628I3502J-1D01*
G03Y244872I-159J122D01*
G02X394998Y246999I2781J2128D01*
G01Y247000D01*
G02X402002I3502J0D01*
G01Y246999D01*
G02X401281Y244872I-3502J1D01*
G03Y244628I159J-122D01*
G02X402002Y242500I-2781J-2128D01*
G02X401959Y241949I-3502J-4D01*
G01X401952Y241908D01*
X401973Y241828D01*
X402178Y241564D01*
G03X402317Y241488I158J123D01*
G01X402318D01*
G02X405502Y238000I-319J-3488D01*
G01Y237998D01*
G02X405202Y236581I-3502J1D01*
G03Y236419I183J-81D01*
G02X405502Y235002I-3202J-1418D01*
G01Y235000D01*
G02X398498I-3502J0D01*
G01Y235002D01*
G02X398798Y236419I3502J-1D01*
G03Y236581I-183J81D01*
G02X398498Y238000I3202J1418D01*
G02X398541Y238551I3502J4D01*
G01X398548Y238592D01*
X398527Y238672D01*
X398322Y238936D01*
G03X398183Y239012I-158J-123D01*
G01X398182D01*
G02X394998Y242500I319J3488D01*
G37*
G36*
G01X548498Y243500D02*
Y243502D01*
G02X548913Y245156I3502J0D01*
G03Y245344I-176J94D01*
G02X548498Y246998I3087J1654D01*
G01Y247000D01*
G02X555502I3502J0D01*
G01Y246998D01*
G02X555087Y245344I-3502J0D01*
G03Y245156I176J-94D01*
G02X555502Y243500I-3087J-1654D01*
G02X555459Y242949I-3502J-4D01*
G01X555452Y242908D01*
X555473Y242828D01*
X555678Y242564D01*
G03X555817Y242488I158J123D01*
G01X555818D01*
G02X559002Y239000I-319J-3488D01*
G01Y238998D01*
G02X558702Y237581I-3502J1D01*
G03Y237419I183J-81D01*
G02X559002Y236002I-3202J-1418D01*
G01Y236000D01*
G02X551998I-3502J0D01*
G01Y236002D01*
G02X552298Y237419I3502J-1D01*
G03Y237581I-183J81D01*
G02X551998Y239000I3202J1418D01*
G02X552041Y239551I3502J4D01*
G01X552048Y239592D01*
X552027Y239672D01*
X551822Y239936D01*
G03X551683Y240012I-158J-123D01*
G01X551682D01*
G02X548498Y243500I319J3488D01*
G37*
G36*
G01X705978D02*
G02X706404Y245172I3502J-2D01*
G03X706405Y245361I-176J95D01*
G02X705998Y246999I3095J1639D01*
G01Y247000D01*
G02X713002I3502J0D01*
G02X712577Y245328I-3501J0D01*
G03X712576Y245139I176J-95D01*
G02X712984Y243500I-3095J-1641D01*
G02X712940Y242949I-3503J2D01*
G01X712933Y242908D01*
X712954Y242828D01*
X713159Y242564D01*
G03X713298Y242488I158J123D01*
G01X713299D01*
G02X716484Y239000I-317J-3488D01*
G02X716183Y237581I-3503J2D01*
G03Y237419I183J-81D01*
G02X716484Y236000I-3202J-1421D01*
G02X709478I-3503J0D01*
G02X709779Y237419I3503J-2D01*
G03Y237581I-183J81D01*
G02X709478Y239000I3202J1421D01*
G02X709522Y239551I3503J-2D01*
G01X709529Y239592D01*
X709508Y239672D01*
X709303Y239936D01*
G03X709164Y240012I-158J-123D01*
G01X709163D01*
G02X705978Y243500I317J3488D01*
G37*
G36*
G01X238998Y243000D02*
Y243001D01*
G02X239719Y245128I3502J-1D01*
G03Y245372I-159J122D01*
G02X238998Y247499I2781J2128D01*
G01Y247500D01*
G02X246002I3502J0D01*
G01Y247499D01*
G02X245281Y245372I-3502J1D01*
G03Y245128I159J-122D01*
G02X246002Y243000I-2781J-2128D01*
G02X245959Y242449I-3502J-4D01*
G01X245952Y242408D01*
X245973Y242328D01*
X246178Y242064D01*
G03X246317Y241988I158J123D01*
G01X246318D01*
G02X249502Y238500I-319J-3488D01*
G01Y238498D01*
G02X249202Y237081I-3502J1D01*
G03Y236919I183J-81D01*
G02X249502Y235502I-3202J-1418D01*
G01Y235500D01*
G02X242498I-3502J0D01*
G01Y235502D01*
G02X242798Y236919I3502J-1D01*
G03Y237081I-183J81D01*
G02X242498Y238500I3202J1418D01*
G02X242541Y239051I3502J4D01*
G01X242548Y239092D01*
X242527Y239172D01*
X242322Y239436D01*
G03X242183Y239512I-158J-123D01*
G01X242182D01*
G02X238998Y243000I319J3488D01*
G37*
G36*
G01X818898Y66932D02*
X905512D01*
G02Y27556I0J-19688D01*
G01X818898D01*
G02Y66932I0J19688D01*
G37*
G36*
G01X634698Y44000D02*
Y44003D01*
G02X634903Y45183I3502J-1D01*
G03Y45317I-188J67D01*
G02X634698Y46497I3297J1181D01*
G01Y46500D01*
G02X638058Y49999I3502J0D01*
G03X638215Y50086I-8J200D01*
G02X641100Y51602I2885J-1987D01*
G02X644602Y48100I0J-3502D01*
G02X643352Y45417I-3503J-1D01*
G03X643350Y45416I86J-174D01*
G03X643280Y45271I130J-152D01*
G01X643269Y44973D01*
G03X643330Y44822I200J-7D01*
G02X644402Y42300I-2431J-2522D01*
G02X640900Y38798I-3502J0D01*
G02X637939Y40429I0J3503D01*
G03X637793Y40521I-169J-107D01*
G02X634698Y44000I408J3479D01*
G37*
G36*
G01X1018570Y169974D02*
X1018622Y170080D01*
G03X1018636Y170225I-178J90D01*
G02X1018498Y171195I3364J973D01*
G01Y171200D01*
G02X1025502I3502J0D01*
G02X1023239Y167924I-3503J0D01*
G03X1023130Y167826I70J-188D01*
G01X1023078Y167720D01*
G03X1023064Y167575I178J-90D01*
G02X1023202Y166600I-3364J-973D01*
G02X1023053Y165589I-3502J0D01*
G01X1023042Y165551D01*
X1023049Y165476D01*
X1023194Y165193D01*
G03X1023305Y165095I178J90D01*
G01X1023306D01*
G02X1025670Y161783I-1138J-3312D01*
G02X1024458Y159133I-3503J0D01*
G03X1024389Y158982I131J-151D01*
G01Y158678D01*
G03X1024458Y158527I200J0D01*
G02X1025670Y155877I-2291J-2650D01*
G01Y155875D01*
G02X1022168Y152374I-3502J1D01*
G02X1021810Y152393I6J3503D01*
G01X1021764Y152398D01*
X1021678Y152366D01*
X1021427Y152103D01*
G03X1021374Y151937I145J-138D01*
G01Y151936D01*
G02X1021412Y151424I-3465J-515D01*
G02X1014406I-3503J0D01*
G02X1014645Y152693I3503J-3D01*
G03X1014641Y152847I-187J72D01*
G02X1014334Y154280I3196J1434D01*
G02X1015483Y156874I3503J0D01*
G03X1015548Y157037I-134J148D01*
G02X1015538Y157310I3492J265D01*
G02X1015838Y158728I3502J0D01*
G03X1015837Y158891I-183J80D01*
G02X1015528Y160330I3194J1438D01*
G02X1017278Y163363I3503J0D01*
G03X1017377Y163515I-100J173D01*
G01X1017411Y163837D01*
G03X1017348Y164005I-199J21D01*
G01X1017347Y164006D01*
G02X1016198Y166600I2354J2594D01*
G02X1018461Y169876I3503J0D01*
G03X1018570Y169974I-70J188D01*
G37*
G36*
G01X568780Y268552D02*
G02Y285856I0J8652D01*
G01X568781D01*
G02X575949Y282049I0J-8652D01*
G01X575977Y282008D01*
X576064Y281961D01*
X576496D01*
X576583Y282008D01*
X576611Y282049D01*
G02X583779Y285856I7168J-4845D01*
G01X583780D01*
G02Y268552I0J-8652D01*
G01X583779D01*
G02X576611Y272359I0J8652D01*
G01X576583Y272400D01*
X576496Y272447D01*
X576064D01*
X575977Y272400D01*
X575949Y272359D01*
G02X568781Y268552I-7168J4845D01*
G01X568780D01*
G37*
G36*
G01X726261D02*
G02Y285856I0J8652D01*
G01X726262D01*
G02X733430Y282049I0J-8652D01*
G01X733458Y282008D01*
X733545Y281961D01*
X733977D01*
X734064Y282008D01*
X734092Y282049D01*
G02X741260Y285856I7168J-4845D01*
G01X741261D01*
G02Y268552I0J-8652D01*
G01X741260D01*
G02X734092Y272359I0J8652D01*
G01X734064Y272400D01*
X733977Y272447D01*
X733545D01*
X733458Y272400D01*
X733430Y272359D01*
G02X726262Y268552I-7168J4845D01*
G01X726261D01*
G37*
G36*
G01X434499Y286688D02*
G02X436391Y286133I0J-3502D01*
G03X436607I108J168D01*
G02X440391I1892J-2948D01*
G03X440607I108J168D01*
G02X442499Y286688I1892J-2947D01*
G01X442501D01*
G02X446002Y283186I-1J-3502D01*
G02X445446Y281294I-3503J2D01*
G03Y281078I169J-108D01*
G02X446002Y279186I-2947J-1894D01*
G02X445446Y277294I-3503J2D01*
G03Y277078I169J-108D01*
G02X446002Y275186I-2947J-1894D01*
G02X445446Y273294I-3503J2D01*
G03Y273078I169J-108D01*
G02X446002Y271186I-2947J-1894D01*
G02X442499Y267684I-3503J1D01*
G02X440607Y268239I0J3502D01*
G03X440391I-108J-168D01*
G02X436607I-1892J2948D01*
G03X436391I-108J-168D01*
G02X434499Y267684I-1892J2947D01*
G02X431355Y269642I0J3503D01*
G03X431232Y269746I-180J-88D01*
G01X430908Y269840D01*
X430825Y269829D01*
X430789Y269807D01*
G02X426299Y268552I-4488J7398D01*
G02X419130Y272359I-1J8652D01*
G01X419102Y272400D01*
X419015Y272447D01*
X418583D01*
X418496Y272400D01*
X418468Y272359D01*
G02X411300Y268552I-7168J4845D01*
G01X411299D01*
G02Y285856I0J8652D01*
G01X411300D01*
G02X418468Y282049I0J-8652D01*
G01X418496Y282008D01*
X418583Y281961D01*
X419015D01*
X419102Y282008D01*
X419130Y282049D01*
G02X426299Y285856I7168J-4845D01*
G02X430802Y284593I2J-8652D01*
G03X430962Y284571I105J170D01*
G01X431244Y284652D01*
G03X431367Y284754I-55J192D01*
G01X431368Y284755D01*
G02X434499Y286688I3131J-1569D01*
G37*
G36*
G01X943886Y562188D02*
X1030500D01*
G02Y522812I0J-19688D01*
G01X943886D01*
G02Y562188I0J19688D01*
G37*
G36*
G01X1140000Y168798D02*
X1139998D01*
G02X1138250Y169266I1J3502D01*
G03X1138050I-100J-173D01*
G02X1136302Y168798I-1749J3034D01*
G01X1136300D01*
G02Y175802I0J3502D01*
G01X1136302D01*
G02X1138050Y175334I-1J-3502D01*
G03X1138250I100J173D01*
G02X1139998Y175802I1749J-3034D01*
G01X1140000D01*
G02Y168798I0J-3502D01*
G37*
G36*
G01X1143490Y180058D02*
G02X1141998Y180392I1J3503D01*
G03X1141828I-85J-181D01*
G02X1140336Y180058I-1493J3169D01*
G02Y187062I0J3502D01*
G02X1141828Y186728I-1J-3503D01*
G03X1141998I85J181D01*
G02X1143490Y187062I1493J-3169D01*
G02Y180058I0J-3502D01*
G37*
G36*
G01X1079500Y181072D02*
G02Y188078I0J3503D01*
G02X1081968Y187060I-1J-3503D01*
G01X1081969Y187059D01*
G03X1082109Y187002I140J143D01*
G01X1082391D01*
G03X1082531Y187059I0J200D01*
G01X1082532Y187060D01*
G02X1085000Y188078I2469J-2485D01*
G02Y181072I0J-3503D01*
G02X1082532Y182090I1J3503D01*
G01X1082531Y182091D01*
G03X1082391Y182148I-140J-143D01*
G01X1082109D01*
G03X1081969Y182091I0J-200D01*
G01X1081968Y182090D01*
G02X1079500Y181072I-2469J2485D01*
G37*
G36*
G01X884000Y286978D02*
G02X885892Y286422I-2J-3503D01*
G03X886108I108J169D01*
G02X888000Y286978I1894J-2947D01*
G02X890917Y285414I0J-3502D01*
G01X890945Y285373D01*
X891033Y285325D01*
X891467D01*
X891555Y285373D01*
X891583Y285414D01*
G02X894500Y286978I2917J-1938D01*
G02Y279972I0J-3503D01*
G02X891583Y281536I0J3502D01*
G01X891555Y281577D01*
X891467Y281625D01*
X891033D01*
X890945Y281577D01*
X890917Y281536D01*
G02X888000Y279972I-2917J1938D01*
G02X886108Y280528I2J3503D01*
G03X885892I-108J-169D01*
G02X884000Y279972I-1894J2947D01*
G02X881083Y281536I0J3502D01*
G01X881055Y281577D01*
X880967Y281625D01*
X880533D01*
X880445Y281577D01*
X880417Y281536D01*
G02X877500Y279972I-2917J1938D01*
G02Y286978I0J3503D01*
G02X880417Y285414I0J-3502D01*
G01X880445Y285373D01*
X880533Y285325D01*
X880967D01*
X881055Y285373D01*
X881083Y285414D01*
G02X884000Y286978I2917J-1938D01*
G37*
G36*
G01X905000D02*
G02X906892Y286422I-2J-3503D01*
G03X907108I108J169D01*
G02X909000Y286978I1894J-2947D01*
G02X911917Y285414I0J-3502D01*
G01X911945Y285373D01*
X912033Y285325D01*
X912467D01*
X912555Y285373D01*
X912583Y285414D01*
G02X915500Y286978I2917J-1938D01*
G02Y279972I0J-3503D01*
G02X912583Y281536I0J3502D01*
G01X912555Y281577D01*
X912467Y281625D01*
X912033D01*
X911945Y281577D01*
X911917Y281536D01*
G02X909000Y279972I-2917J1938D01*
G02X907108Y280528I2J3503D01*
G03X906892I-108J-169D01*
G02X905000Y279972I-1894J2947D01*
G02Y286978I0J3503D01*
G37*
G36*
G01X926998Y315460D02*
G02X934002I3502J0D01*
G01Y315459D01*
G02X933639Y313907I-3502J1D01*
G03Y313731I180J-88D01*
G01X933798Y313404D01*
X933870Y313348D01*
X933916Y313338D01*
G02X936698Y309910I-721J-3428D01*
G02X929694I-3502J0D01*
G01Y309911D01*
G02X930057Y311463I3502J-1D01*
G03Y311639I-180J88D01*
G01X929898Y311966D01*
X929826Y312022D01*
X929780Y312032D01*
G02X926998Y315460I721J3428D01*
G37*
G36*
G01X912758Y337077D02*
G02X916260Y333574I3502J-1D01*
G02X915870Y333596I2J3503D01*
G03X915699Y333532I-23J-199D01*
G01X915449Y333258D01*
X915423Y333167D01*
X915433Y333120D01*
G02X915502Y332425I-3433J-692D01*
G02X915009Y330632I-3502J-1D01*
G03X915036Y330392I172J-102D01*
G02X916002Y327975I-2537J-2415D01*
G02X915621Y326385I-3502J-1D01*
G03X915617Y326211I178J-91D01*
G01X915745Y325927D01*
G03X915877Y325816I182J83D01*
G02X918502Y322425I-878J-3391D01*
G02X911498I-3502J0D01*
G01Y322428D01*
G02X911879Y324015I3502J-2D01*
G03X911883Y324189I-178J91D01*
G01X911755Y324473D01*
G03X911623Y324584I-182J-83D01*
G02X910372Y325194I879J3390D01*
G03X910128I-122J-159D01*
G02X908000Y324472I-2130J2780D01*
G02X905872Y325194I2J3502D01*
G03X905628I-122J-159D01*
G02X903500Y324472I-2130J2780D01*
G02Y331478I0J3503D01*
G02X905628Y330756I-2J-3502D01*
G03X905872I122J159D01*
G02X907999Y331478I2130J-2780D01*
G01X908001D01*
G02X908121Y331475I-28J-3502D01*
G01X908123D01*
G03X908278Y331541I6J200D01*
G01X908513Y331803D01*
X908539Y331887D01*
X908532Y331931D01*
G02X908498Y332425I3468J487D01*
G02X912000Y335928I3502J1D01*
G02X912390Y335906I-2J-3503D01*
G03X912561Y335970I23J199D01*
G01X912811Y336244D01*
X912837Y336335D01*
X912827Y336382D01*
G02X912758Y337077I3433J692D01*
G37*
G36*
G01X593002Y446500D02*
G02X590942Y443308I-3503J0D01*
G03X590834Y443187I82J-182D01*
G02X587500Y440758I-3334J1074D01*
G02X583998Y444260I0J3502D01*
G02X586058Y447452I3503J0D01*
G03X586166Y447573I-82J182D01*
G02X589500Y450002I3334J-1074D01*
G02X593002Y446500I0J-3502D01*
G37*
G36*
G01X940390Y313255D02*
G02X939668Y315385I2781J2130D01*
G02X946674I3503J0D01*
G02X945953Y313258I-3503J2D01*
G03Y313014I159J-122D01*
G02X946674Y310885I-2781J-2128D01*
G02X943172Y307382I-3502J-1D01*
G02X943099Y307383I11J3503D01*
G01X943035Y307384D01*
X942931Y307314D01*
X942752Y306841D01*
X942784Y306719D01*
X942833Y306678D01*
G02X943889Y305132I-2259J-2677D01*
G01X943906Y305083D01*
X943981Y305015D01*
X944362Y304924D01*
G03X944548Y304976I46J195D01*
G02X947000Y305978I2453J-2501D01*
G02Y298972I0J-3503D01*
G02X943686Y301343I1J3503D01*
G01X943669Y301392D01*
X943594Y301460D01*
X943213Y301551D01*
G03X943027Y301499I-46J-195D01*
G02X941174Y300549I-2452J2501D01*
G03X941009Y300337I34J-197D01*
G02X941018Y300075I-3494J-251D01*
G02X940036Y297643I-3503J0D01*
G01X939995Y297601D01*
X939972Y297488D01*
X940121Y297095D01*
G03X940290Y296966I187J70D01*
G01X940291D01*
G02X943141Y295025I-291J-3490D01*
G03X943321Y294914I179J89D01*
G01X943679D01*
G03X943859Y295025I1J200D01*
G02X947000Y296978I3141J-1549D01*
G02Y289974I0J-3502D01*
G02X943859Y291927I0J3502D01*
G03X943679Y292038I-179J-89D01*
G01X943321D01*
G03X943141Y291927I-1J-200D01*
G02X936859I-3141J1550D01*
G03X936679Y292038I-179J-89D01*
G01X936321D01*
G03X936141Y291927I-1J-200D01*
G02X933000Y289974I-3141J1549D01*
G02Y296978I0J3502D01*
G02X936141Y295025I0J-3502D01*
G03X936321Y294914I179J89D01*
G01X936679D01*
G03X936859Y295025I1J200D01*
G02X937480Y295908I3141J-1549D01*
G01X937521Y295950D01*
X937544Y296063D01*
X937395Y296456D01*
G03X937226Y296585I-187J-70D01*
G01X937225D01*
G02X934014Y300075I291J3490D01*
G02X936917Y303526I3503J0D01*
G03X937082Y303738I-34J197D01*
G02X937072Y304000I3493J265D01*
G02X940575Y307502I3503J-1D01*
G01X940646D01*
X940650D01*
X940712Y307501D01*
X940816Y307571D01*
X940995Y308044D01*
X940963Y308166D01*
X940914Y308207D01*
G02X939670Y310885I2258J2677D01*
G02X940390Y313012I3502J0D01*
G03Y313255I-159J122D01*
G37*
G36*
G01X183539Y494498D02*
X183537D01*
G02X182120Y494798I1J3502D01*
G03X181958I-81J-183D01*
G02X180541Y494498I-1418J3202D01*
G01X180539D01*
G02Y501502I0J3502D01*
G01X180541D01*
G02X181958Y501202I-1J-3502D01*
G03X182120I81J183D01*
G02X183537Y501502I1418J-3202D01*
G01X183539D01*
G02Y494498I0J-3502D01*
G37*
G36*
G01X231539D02*
X231537D01*
G02X230120Y494798I1J3502D01*
G03X229958I-81J-183D01*
G02X228541Y494498I-1418J3202D01*
G01X228539D01*
G02Y501502I0J3502D01*
G01X228541D01*
G02X229958Y501202I-1J-3502D01*
G03X230120I81J183D01*
G02X231537Y501502I1418J-3202D01*
G01X231539D01*
G02Y494498I0J-3502D01*
G37*
G36*
G01X279539D02*
X279537D01*
G02X278120Y494798I1J3502D01*
G03X277958I-81J-183D01*
G02X276541Y494498I-1418J3202D01*
G01X276539D01*
G02Y501502I0J3502D01*
G01X276541D01*
G02X277958Y501202I-1J-3502D01*
G03X278120I81J183D01*
G02X279537Y501502I1418J-3202D01*
G01X279539D01*
G02Y494498I0J-3502D01*
G37*
G36*
G01X341019D02*
X341017D01*
G02X339600Y494798I1J3502D01*
G03X339438I-81J-183D01*
G02X338021Y494498I-1418J3202D01*
G01X338019D01*
G02Y501502I0J3502D01*
G01X338021D01*
G02X339438Y501202I-1J-3502D01*
G03X339600I81J183D01*
G02X341017Y501502I1418J-3202D01*
G01X341019D01*
G02Y494498I0J-3502D01*
G37*
G36*
G01X389019D02*
X389017D01*
G02X387600Y494798I1J3502D01*
G03X387438I-81J-183D01*
G02X386021Y494498I-1418J3202D01*
G01X386019D01*
G02Y501502I0J3502D01*
G01X386021D01*
G02X387438Y501202I-1J-3502D01*
G03X387600I81J183D01*
G02X389017Y501502I1418J-3202D01*
G01X389019D01*
G02Y494498I0J-3502D01*
G37*
G36*
G01X437019D02*
X437017D01*
G02X435600Y494798I1J3502D01*
G03X435438I-81J-183D01*
G02X434021Y494498I-1418J3202D01*
G01X434019D01*
G02Y501502I0J3502D01*
G01X434021D01*
G02X435438Y501202I-1J-3502D01*
G03X435600I81J183D01*
G02X437017Y501502I1418J-3202D01*
G01X437019D01*
G02Y494498I0J-3502D01*
G37*
G36*
G01X498500D02*
X498498D01*
G02X497081Y494798I1J3502D01*
G03X496919I-81J-183D01*
G02X495502Y494498I-1418J3202D01*
G01X495500D01*
G02Y501502I0J3502D01*
G01X495502D01*
G02X496919Y501202I-1J-3502D01*
G03X497081I81J183D01*
G02X498498Y501502I1418J-3202D01*
G01X498500D01*
G02Y494498I0J-3502D01*
G37*
G36*
G01X546500D02*
X546498D01*
G02X545081Y494798I1J3502D01*
G03X544919I-81J-183D01*
G02X543502Y494498I-1418J3202D01*
G01X543500D01*
G02Y501502I0J3502D01*
G01X543502D01*
G02X544919Y501202I-1J-3502D01*
G03X545081I81J183D01*
G02X546498Y501502I1418J-3202D01*
G01X546500D01*
G02Y494498I0J-3502D01*
G37*
G36*
G01X594500D02*
X594498D01*
G02X593081Y494798I1J3502D01*
G03X592919I-81J-183D01*
G02X591502Y494498I-1418J3202D01*
G01X591500D01*
G02Y501502I0J3502D01*
G01X591502D01*
G02X592919Y501202I-1J-3502D01*
G03X593081I81J183D01*
G02X594498Y501502I1418J-3202D01*
G01X594500D01*
G02Y494498I0J-3502D01*
G37*
G36*
G01X655981D02*
X655979D01*
G02X654562Y494798I1J3502D01*
G03X654400I-81J-183D01*
G02X652983Y494498I-1418J3202D01*
G01X652981D01*
G02Y501502I0J3502D01*
G01X652983D01*
G02X654400Y501202I-1J-3502D01*
G03X654562I81J183D01*
G02X655979Y501502I1418J-3202D01*
G01X655981D01*
G02Y494498I0J-3502D01*
G37*
G36*
G01X703981D02*
X703979D01*
G02X702562Y494798I1J3502D01*
G03X702400I-81J-183D01*
G02X700983Y494498I-1418J3202D01*
G01X700981D01*
G02Y501502I0J3502D01*
G01X700983D01*
G02X702400Y501202I-1J-3502D01*
G03X702562I81J183D01*
G02X703979Y501502I1418J-3202D01*
G01X703981D01*
G02Y494498I0J-3502D01*
G37*
G36*
G01X751981D02*
X751979D01*
G02X750562Y494798I1J3502D01*
G03X750400I-81J-183D01*
G02X748983Y494498I-1418J3202D01*
G01X748981D01*
G02Y501502I0J3502D01*
G01X748983D01*
G02X750400Y501202I-1J-3502D01*
G03X750562I81J183D01*
G02X751979Y501502I1418J-3202D01*
G01X751981D01*
G02Y494498I0J-3502D01*
G37*
G36*
G01X183539Y514498D02*
X183537D01*
G02X182120Y514798I1J3502D01*
G03X181958I-81J-183D01*
G02X180541Y514498I-1418J3202D01*
G01X180539D01*
G02Y521502I0J3502D01*
G01X180541D01*
G02X181958Y521202I-1J-3502D01*
G03X182120I81J183D01*
G02X183537Y521502I1418J-3202D01*
G01X183539D01*
G02Y514498I0J-3502D01*
G37*
G36*
G01X231539D02*
X231537D01*
G02X230120Y514798I1J3502D01*
G03X229958I-81J-183D01*
G02X228541Y514498I-1418J3202D01*
G01X228539D01*
G02Y521502I0J3502D01*
G01X228541D01*
G02X229958Y521202I-1J-3502D01*
G03X230120I81J183D01*
G02X231537Y521502I1418J-3202D01*
G01X231539D01*
G02Y514498I0J-3502D01*
G37*
G36*
G01X279539D02*
X279537D01*
G02X278120Y514798I1J3502D01*
G03X277958I-81J-183D01*
G02X276541Y514498I-1418J3202D01*
G01X276539D01*
G02Y521502I0J3502D01*
G01X276541D01*
G02X277958Y521202I-1J-3502D01*
G03X278120I81J183D01*
G02X279537Y521502I1418J-3202D01*
G01X279539D01*
G02Y514498I0J-3502D01*
G37*
G36*
G01X341019D02*
X341017D01*
G02X339600Y514798I1J3502D01*
G03X339438I-81J-183D01*
G02X338021Y514498I-1418J3202D01*
G01X338019D01*
G02Y521502I0J3502D01*
G01X338021D01*
G02X339438Y521202I-1J-3502D01*
G03X339600I81J183D01*
G02X341017Y521502I1418J-3202D01*
G01X341019D01*
G02Y514498I0J-3502D01*
G37*
G36*
G01X389019D02*
X389017D01*
G02X387600Y514798I1J3502D01*
G03X387438I-81J-183D01*
G02X386021Y514498I-1418J3202D01*
G01X386019D01*
G02Y521502I0J3502D01*
G01X386021D01*
G02X387438Y521202I-1J-3502D01*
G03X387600I81J183D01*
G02X389017Y521502I1418J-3202D01*
G01X389019D01*
G02Y514498I0J-3502D01*
G37*
G36*
G01X437019D02*
X437017D01*
G02X435600Y514798I1J3502D01*
G03X435438I-81J-183D01*
G02X434021Y514498I-1418J3202D01*
G01X434019D01*
G02Y521502I0J3502D01*
G01X434021D01*
G02X435438Y521202I-1J-3502D01*
G03X435600I81J183D01*
G02X437017Y521502I1418J-3202D01*
G01X437019D01*
G02Y514498I0J-3502D01*
G37*
G36*
G01X498500D02*
X498498D01*
G02X497081Y514798I1J3502D01*
G03X496919I-81J-183D01*
G02X495502Y514498I-1418J3202D01*
G01X495500D01*
G02Y521502I0J3502D01*
G01X495502D01*
G02X496919Y521202I-1J-3502D01*
G03X497081I81J183D01*
G02X498498Y521502I1418J-3202D01*
G01X498500D01*
G02Y514498I0J-3502D01*
G37*
G36*
G01X546500D02*
X546498D01*
G02X545081Y514798I1J3502D01*
G03X544919I-81J-183D01*
G02X543502Y514498I-1418J3202D01*
G01X543500D01*
G02Y521502I0J3502D01*
G01X543502D01*
G02X544919Y521202I-1J-3502D01*
G03X545081I81J183D01*
G02X546498Y521502I1418J-3202D01*
G01X546500D01*
G02Y514498I0J-3502D01*
G37*
G36*
G01X594500D02*
X594498D01*
G02X593081Y514798I1J3502D01*
G03X592919I-81J-183D01*
G02X591502Y514498I-1418J3202D01*
G01X591500D01*
G02Y521502I0J3502D01*
G01X591502D01*
G02X592919Y521202I-1J-3502D01*
G03X593081I81J183D01*
G02X594498Y521502I1418J-3202D01*
G01X594500D01*
G02Y514498I0J-3502D01*
G37*
G36*
G01X655981D02*
X655979D01*
G02X654562Y514798I1J3502D01*
G03X654400I-81J-183D01*
G02X652983Y514498I-1418J3202D01*
G01X652981D01*
G02Y521502I0J3502D01*
G01X652983D01*
G02X654400Y521202I-1J-3502D01*
G03X654562I81J183D01*
G02X655979Y521502I1418J-3202D01*
G01X655981D01*
G02Y514498I0J-3502D01*
G37*
G36*
G01X703981D02*
X703979D01*
G02X702562Y514798I1J3502D01*
G03X702400I-81J-183D01*
G02X700983Y514498I-1418J3202D01*
G01X700981D01*
G02Y521502I0J3502D01*
G01X700983D01*
G02X702400Y521202I-1J-3502D01*
G03X702562I81J183D01*
G02X703979Y521502I1418J-3202D01*
G01X703981D01*
G02Y514498I0J-3502D01*
G37*
G36*
G01X751981D02*
X751979D01*
G02X750562Y514798I1J3502D01*
G03X750400I-81J-183D01*
G02X748983Y514498I-1418J3202D01*
G01X748981D01*
G02Y521502I0J3502D01*
G01X748983D01*
G02X750400Y521202I-1J-3502D01*
G03X750562I81J183D01*
G02X751979Y521502I1418J-3202D01*
G01X751981D01*
G02Y514498I0J-3502D01*
G37*
G36*
G01X1075308Y93848D02*
G02X1077200Y94402I1890J-2948D01*
G02Y87398I0J-3502D01*
G02X1075308Y87952I-2J3502D01*
G03X1075092I-108J-168D01*
G02X1073200Y87398I-1890J2948D01*
G02Y94402I0J3502D01*
G02X1075092Y93848I2J-3502D01*
G03X1075308I108J168D01*
G37*
G36*
G01X1181839Y169249D02*
G02X1183021Y169454I1181J-3297D01*
G02X1184203Y169249I1J-3502D01*
G03X1184339I68J188D01*
G02X1185521Y169454I1181J-3297D01*
G02X1186928Y169160I2J-3502D01*
G03X1187094Y169162I81J183D01*
G02X1188600Y169502I1505J-3162D01*
G02X1192102Y166000I0J-3502D01*
G02X1191763Y164496I-3502J-1D01*
G03X1191764Y164322I181J-86D01*
G02X1192120Y162782I-3146J-1538D01*
G02X1188618Y159280I-3502J0D01*
G02X1186979Y159687I0J3502D01*
G03X1186812Y159696I-93J-177D01*
G02X1185521Y159450I-1289J3256D01*
G02X1184339Y159655I-1J3502D01*
G03X1184203I-68J-188D01*
G02X1183021Y159450I-1181J3297D01*
G02X1181839Y159655I-1J3502D01*
G03X1181703I-68J-188D01*
G02X1180521Y159450I-1181J3297D01*
G02X1179102Y159750I-1J3502D01*
G03X1178940I-81J-183D01*
G02X1177521Y159450I-1418J3202D01*
G02X1174018Y162952I-1J3502D01*
G02X1174319Y164371I3503J-2D01*
G03Y164533I-183J81D01*
G02X1174018Y165952I3202J1421D01*
G02X1177521Y169454I3503J-1D01*
G02X1178940Y169154I1J-3502D01*
G03X1179102I81J183D01*
G02X1180521Y169454I1418J-3202D01*
G02X1181703Y169249I1J-3502D01*
G03X1181839I68J188D01*
G37*
G36*
G01X1168298Y209581D02*
G02X1167998Y211000I3202J1418D01*
G02X1168298Y212419I3502J1D01*
G03Y212581I-183J81D01*
G02X1167998Y214000I3202J1418D01*
G02X1171500Y217502I3502J0D01*
G02X1172919Y217202I1J-3502D01*
G03X1173081I81J183D01*
G02X1174500Y217502I1418J-3202D01*
G02X1178002Y214000I0J-3502D01*
G02X1177702Y212581I-3502J-1D01*
G03Y212419I183J-81D01*
G02X1178002Y211000I-3202J-1418D01*
G02X1177702Y209581I-3502J-1D01*
G03Y209419I183J-81D01*
G02X1178002Y208000I-3202J-1418D01*
G02X1177702Y206581I-3502J-1D01*
G03Y206419I183J-81D01*
G02X1178002Y205000I-3202J-1418D01*
G02X1174500Y201498I-3502J0D01*
G02X1173081Y201798I-1J3502D01*
G03X1172919I-81J-183D01*
G02X1171500Y201498I-1418J3202D01*
G02X1167998Y205000I0J3502D01*
G02X1168298Y206419I3502J1D01*
G03Y206581I-183J81D01*
G02X1167998Y208000I3202J1418D01*
G02X1168298Y209419I3502J1D01*
G03Y209581I-183J81D01*
G37*
G54D57*
X184349Y212651D03*
X183815Y220903D03*
X247441Y305975D03*
X404921D03*
X562402D03*
X719883D03*
X1024340Y146600D03*
X430019Y444260D03*
X1094024Y179500D03*
X1120200Y176500D03*
X1129000Y157000D03*
Y166500D03*
Y176500D03*
X748075Y366500D03*
X545063Y340339D03*
X538780Y445025D03*
X549500Y445024D03*
X893363Y298740D03*
X883000Y293925D03*
X880000Y312855D03*
X875000Y347273D03*
X313571Y340552D03*
X290720Y340338D03*
X926000Y283475D03*
X914500Y292000D03*
X905941Y306500D03*
X904500Y292000D03*
X173265Y340552D03*
X905941Y320366D03*
X923740Y345500D03*
X223819Y445025D03*
X901063Y352340D03*
X447255Y340339D03*
X432019Y452025D03*
X940000Y283800D03*
X941035Y344474D03*
X933357Y344843D03*
X473095Y340339D03*
X943885Y352385D03*
X933196Y353360D03*
X381299Y445025D03*
X696261Y445024D03*
X1158000Y179000D03*
X1092000Y82500D03*
X1158200Y137700D03*
G54D61*
X1226024Y286929D03*
G54D54*
X48780Y329724D03*
G54D56*
X268000Y220315D03*
X823981D03*
X666500D03*
X735981D03*
X779981D03*
X516500D03*
X578500D03*
X622500D03*
X312500D03*
X357000D03*
X428500D03*
X472500D03*
G54D59*
X596185Y539000D03*
X548185D03*
X500185D03*
X438704D03*
X390704D03*
X342704D03*
X281224D03*
X185224D03*
X705666D03*
X753666D03*
X657666D03*
X233224D03*
G54D51*
X19922Y367716D03*
Y214173D03*
G54D52*
X175000Y100500D03*
X1271654Y636929D03*
X619685D03*
G54D60*
X1226024Y174429D03*
G54D53*
X108858Y482205D03*
G54D55*
X249252Y129685D03*
X529252D03*
X665059Y149408D03*
X980059D03*
X1226024Y399429D03*
G54D58*
X964460Y16950D03*
G54D10*
X3005Y19808D03*
Y34808D03*
Y59808D03*
X7595Y128373D03*
X3005Y145238D03*
Y165238D03*
Y185238D03*
Y205238D03*
Y225238D03*
Y245238D03*
Y265238D03*
Y285238D03*
Y305238D03*
Y325238D03*
Y345238D03*
Y365238D03*
Y385238D03*
Y405238D03*
Y425238D03*
Y445238D03*
X3023Y524312D03*
Y549312D03*
X4540Y566003D03*
X34582Y3004D03*
X14811Y3732D03*
X12767Y72072D03*
X27271Y127298D03*
X19558Y454589D03*
X9913Y510026D03*
X20498Y575739D03*
X54582Y3004D03*
X63436Y353962D03*
X39549Y454916D03*
X40498Y575739D03*
X60498D03*
X94582Y3004D03*
X74582D03*
X80498Y575739D03*
X114582Y3004D03*
X108600Y258560D03*
X111600D03*
X108600Y261560D03*
X111600D03*
X108600Y255560D03*
X111600D03*
X100498Y575739D03*
X120498D03*
X154582Y3004D03*
X134582D03*
X153480Y213350D03*
X150634Y219063D03*
X155140Y240230D03*
X154840Y244730D03*
X155034Y228063D03*
Y224563D03*
X152334Y223063D03*
Y226563D03*
Y230063D03*
X155034Y231563D03*
X140498Y575739D03*
X174582Y3004D03*
X172934Y219110D03*
X184349Y212651D03*
X183900Y216830D03*
X178265Y213443D03*
X175976Y218775D03*
X172712Y222263D03*
X183815Y220903D03*
X165840Y247805D03*
X169840D03*
X166068Y238749D03*
X173869Y228168D03*
X175481Y225183D03*
X160017Y237764D03*
X161400Y323200D03*
X173265Y340552D03*
X183539Y518000D03*
X180539Y498000D03*
X183539D03*
X180539Y518000D03*
X214582Y3004D03*
X194582D03*
X189760Y242100D03*
Y245100D03*
X192760Y242100D03*
Y245100D03*
X195760Y242100D03*
Y245100D03*
X198760Y242100D03*
Y245100D03*
X201760Y242100D03*
Y245100D03*
X208071Y305975D03*
X203575Y297500D03*
X212925Y315500D03*
X234582Y3004D03*
X246000Y238500D03*
X242500Y243000D03*
Y247500D03*
X218500Y305000D03*
X226975D03*
X235975D03*
X239567Y305975D03*
X230425Y313605D03*
X221425Y313000D03*
X223819Y445025D03*
X231539Y518000D03*
X228539Y498000D03*
X231539D03*
X228539Y518000D03*
X254582Y3004D03*
X246000Y235500D03*
X247441Y305975D03*
X294582Y3004D03*
X274582D03*
X297000Y206000D03*
Y203500D03*
Y198500D03*
Y196000D03*
X290720Y340338D03*
X279539Y518000D03*
X276539Y498000D03*
X279539D03*
X276539Y518000D03*
X314582Y3004D03*
X318500Y206000D03*
Y203500D03*
Y198500D03*
Y196000D03*
X313571Y340552D03*
X354582Y3004D03*
X334582D03*
X340000Y206000D03*
Y203500D03*
Y198500D03*
Y196000D03*
X361500Y206000D03*
Y203500D03*
Y198500D03*
Y196000D03*
X341019Y518000D03*
X338019Y498000D03*
X341019D03*
X338019Y518000D03*
X374582Y3004D03*
X383000Y206000D03*
Y203500D03*
Y198500D03*
Y196000D03*
X375475Y305000D03*
X383975D03*
X365551Y305975D03*
X382963Y316400D03*
Y313750D03*
X381299Y445025D03*
X389019Y518000D03*
X386019Y498000D03*
X389019D03*
X386019Y518000D03*
X414582Y3004D03*
X394582D03*
X404500Y206000D03*
Y203500D03*
Y198500D03*
Y196000D03*
X402000Y235000D03*
Y238000D03*
X398500Y247000D03*
Y242500D03*
X393000Y305000D03*
X397047Y305975D03*
X404921D03*
X434582Y3004D03*
X426000Y206000D03*
Y203500D03*
Y198500D03*
Y196000D03*
X442499Y279186D03*
X438499D03*
X434499D03*
X442499Y275186D03*
X438499D03*
X434499D03*
X442499Y271186D03*
X438499D03*
X434499D03*
Y283186D03*
X438499D03*
X442499D03*
X447255Y340339D03*
X430019Y444260D03*
X432019Y452025D03*
X437019Y518000D03*
X434019Y498000D03*
X437019D03*
X434019Y518000D03*
X474582Y3004D03*
X454582D03*
X473095Y340339D03*
X494582Y3004D03*
X498500Y498000D03*
X495500D03*
X498500Y518000D03*
X495500D03*
X534582Y3004D03*
X514582D03*
X533475Y305500D03*
X523032Y305975D03*
X518575Y295500D03*
X539619Y316400D03*
Y313400D03*
X538780Y445025D03*
X554582Y3004D03*
X555500Y239000D03*
Y236000D03*
X552000Y243500D03*
Y247000D03*
X542475Y305500D03*
X551475D03*
X554528Y305975D03*
X562402D03*
X545063Y340339D03*
X549500Y445024D03*
X546500Y498000D03*
X543500D03*
X546500Y518000D03*
X543500D03*
X594582Y3004D03*
X574582D03*
X587500Y444260D03*
X589500Y446500D03*
X594500Y498000D03*
X591500D03*
X594500Y518000D03*
X591500D03*
X614582Y3004D03*
X604500Y205500D03*
Y203000D03*
Y198000D03*
Y195500D03*
X626000Y205500D03*
Y203000D03*
Y198000D03*
Y195500D03*
X654582Y3004D03*
X634582D03*
X647975Y37000D03*
X640900Y42300D03*
X647999Y33000D03*
X660200Y56800D03*
X655300D03*
X652300D03*
X638200Y44000D03*
Y46500D03*
X641100Y48100D03*
X647500Y205500D03*
Y203000D03*
Y198000D03*
Y195500D03*
X655981Y518000D03*
Y498000D03*
X652981D03*
Y518000D03*
X674582Y3004D03*
X684525Y32500D03*
Y36500D03*
X690075Y39500D03*
X683600Y56800D03*
X679000D03*
X676000D03*
X686500D03*
X671100D03*
X668100D03*
X663200D03*
X669000Y205500D03*
Y203000D03*
Y198000D03*
Y195500D03*
X680513Y305975D03*
X676075Y299600D03*
X680400Y310500D03*
X714582Y3004D03*
X694582D03*
X699500Y34500D03*
X703740Y41000D03*
X707000Y32000D03*
X694425Y29500D03*
X696900Y53300D03*
X694200D03*
X691400D03*
X689900Y56600D03*
X693000D03*
X696100Y56700D03*
X706000Y61975D03*
X703740Y54118D03*
X690500Y205500D03*
Y203000D03*
Y198000D03*
Y195500D03*
X711990D03*
Y198000D03*
Y203000D03*
Y205500D03*
X709500Y247000D03*
X709481Y243500D03*
X712981Y236000D03*
Y239000D03*
X716100Y255987D03*
X700040Y258960D03*
X712009Y305975D03*
X708956Y305500D03*
X690956D03*
X700000D03*
X694406Y295500D03*
X697100Y313400D03*
X704400Y358600D03*
X697900Y352500D03*
X707750Y358750D03*
X696261Y445024D03*
X703981Y518000D03*
Y498000D03*
X700981D03*
Y518000D03*
X734582Y3004D03*
X733490Y195500D03*
Y198000D03*
Y203000D03*
Y205500D03*
X719883Y305975D03*
X724000Y294500D03*
X732100Y332400D03*
X735075Y326000D03*
Y336000D03*
X731925D03*
X732000Y326000D03*
X742500Y361500D03*
X774582Y3004D03*
X754582D03*
X761560Y38500D03*
X758760D03*
X756160D03*
X761560Y30000D03*
X758760D03*
X756160D03*
X758900Y27400D03*
X761560Y55500D03*
X758760D03*
X756160D03*
X761560Y47000D03*
X758760D03*
X756160D03*
X761560Y64000D03*
X758760D03*
X756160D03*
X754000Y353500D03*
Y356957D03*
X748075Y366500D03*
X748981Y498000D03*
X751981D03*
Y518000D03*
X748981D03*
X794582Y3004D03*
X797854Y259539D03*
X784855Y265184D03*
X790000Y259612D03*
X794900Y265979D03*
X806000Y265075D03*
X806500Y285500D03*
X786500Y336484D03*
X779100Y326820D03*
X798400Y323900D03*
X786500Y316700D03*
X793800Y323880D03*
X781500Y362700D03*
X802975Y362000D03*
X792000Y358000D03*
X834582Y3004D03*
X814582D03*
X809500Y259430D03*
X808500Y272925D03*
X831000Y260500D03*
X836000D03*
X826000Y260525D03*
X833500Y268575D03*
X821000Y270525D03*
X816000D03*
X827602Y283500D03*
X836500Y302500D03*
X814500Y293000D03*
X819500Y329000D03*
X827500D03*
X819500Y318500D03*
X808425Y334000D03*
X831750Y318250D03*
X825941Y339560D03*
X813975Y362000D03*
Y357000D03*
X835610Y355590D03*
X827000Y360475D03*
Y352500D03*
X808425Y344000D03*
X854582Y3004D03*
X849490Y196000D03*
Y198500D03*
Y203500D03*
Y206000D03*
X863600Y208900D03*
X841000Y260525D03*
X846000D03*
X851000D03*
X856000D03*
X843500Y268575D03*
X853500D03*
X850750Y250750D03*
X848075Y306500D03*
X853000Y303500D03*
X861600Y304600D03*
X845000Y303000D03*
X837575Y321000D03*
X865000Y313200D03*
X844760Y336077D03*
X848500Y335800D03*
X850500Y360075D03*
Y366000D03*
X847500D03*
X856500D03*
X859500D03*
X865500D03*
X843843Y354342D03*
X864500Y358500D03*
X894582Y3004D03*
X874582D03*
X868000Y271500D03*
X894500Y283475D03*
X884000D03*
X877500D03*
X893363Y298740D03*
X883000Y293925D03*
X867000Y291260D03*
X870000Y304525D03*
X875000D03*
X880000D03*
X888000Y283475D03*
X870000Y312788D03*
X880000Y312855D03*
X875000Y347273D03*
X877500Y366000D03*
X874500D03*
X884000D03*
X887000D03*
X893500D03*
X868500D03*
X878000Y358475D03*
X883000Y358500D03*
X874000Y358475D03*
X885500Y352925D03*
X869000Y360500D03*
X914582Y3004D03*
X915500Y283475D03*
X914500Y292000D03*
X905000Y283475D03*
X905941Y306500D03*
X909000Y283475D03*
X904500Y292000D03*
X912500Y327975D03*
X916260Y337077D03*
X908000Y327975D03*
X915000Y322425D03*
X912000Y332425D03*
X905941Y320366D03*
X903500Y327975D03*
X896500Y366000D03*
X906000D03*
X903000D03*
X912500D03*
X915500D03*
X922000D03*
X901063Y352340D03*
X916260Y355000D03*
X910992Y361075D03*
X920000Y355525D03*
X923740Y345500D03*
X934582Y3004D03*
X940575Y304000D03*
X933000Y293476D03*
X940000D03*
X947000D03*
X926000Y283475D03*
X937516Y300075D03*
X947000Y302475D03*
X940000Y283800D03*
X933196Y309910D03*
X930500Y315460D03*
X943172Y310885D03*
X943171Y315385D03*
X935516Y361075D03*
X925000Y366000D03*
X944000D03*
X941000D03*
X934500D03*
X950500D03*
X953500D03*
X931500D03*
X927000Y361075D03*
X941035Y344474D03*
X927000Y357925D03*
X943885Y352385D03*
X933357Y344843D03*
X933196Y353360D03*
X940498Y575739D03*
X974582Y3004D03*
X954582D03*
X960498Y575739D03*
X980498D03*
X994582Y3004D03*
X1000498Y575739D03*
X1034582Y3004D03*
X1014582D03*
X1022575Y100925D03*
Y115500D03*
X1034500Y142000D03*
Y145000D03*
X1037000Y146300D03*
X1037500Y142000D03*
X1036500Y153500D03*
X1043936Y145745D03*
X1019040Y157310D03*
X1019030Y160330D03*
X1022168Y155877D03*
Y161783D03*
X1017909Y151424D03*
X1017837Y154280D03*
X1024340Y146600D03*
X1016614Y187267D03*
Y190267D03*
X1036500Y172000D03*
Y163000D03*
X1039016Y189075D03*
Y183027D03*
X1039538Y179208D03*
X1039016Y185925D03*
X1022000Y171200D03*
X1019700Y166600D03*
X1016614Y197767D03*
X1020498Y575739D03*
X1040498D03*
X1054582Y3004D03*
X1057525Y130500D03*
X1065000Y156425D03*
X1049356Y143900D03*
X1047159Y141487D03*
X1054500Y148500D03*
X1048000Y153500D03*
X1057525Y134000D03*
Y138600D03*
X1073154Y140800D03*
X1057500Y155877D03*
X1070715Y146500D03*
X1063500Y159814D03*
X1070715Y178585D03*
X1048000Y172000D03*
Y163000D03*
X1060500Y164500D03*
X1062500Y191500D03*
X1067000D03*
X1070000D03*
X1058000D03*
X1053830Y191670D03*
X1067701Y270442D03*
X1061600Y276242D03*
X1067679Y317942D03*
X1061600Y323742D03*
X1067707Y365442D03*
X1061600Y359642D03*
X1067531Y412942D03*
X1060984Y418742D03*
X1067730Y460352D03*
X1061600Y466242D03*
X1067866Y507629D03*
X1061600Y513742D03*
X1060498Y575739D03*
X1094582Y3004D03*
X1074582D03*
X1092000Y82500D03*
X1087000Y100000D03*
X1073200Y90900D03*
X1077200D03*
X1084325Y130197D03*
X1100075Y139925D03*
X1084260Y152600D03*
X1073154Y137800D03*
X1082000Y143600D03*
X1092000Y159500D03*
X1094500Y143144D03*
X1084401Y159260D03*
X1094024Y179500D03*
X1085000Y184575D03*
X1079500D03*
X1085525Y167500D03*
Y171000D03*
Y174500D03*
Y164000D03*
X1097500Y203700D03*
X1100000D03*
X1073500Y191500D03*
X1086500Y356000D03*
X1090500Y376500D03*
X1080418Y373600D03*
X1090443Y417343D03*
X1086500Y403500D03*
X1074316Y406925D03*
X1080498Y575739D03*
X1100498D03*
X1114582Y3004D03*
X1115800Y126600D03*
X1113500Y147500D03*
X1130125Y135940D03*
X1126075Y135973D03*
X1121238Y144500D03*
X1104500Y136524D03*
X1120524Y138457D03*
X1129000Y157000D03*
X1120200D03*
X1115425Y138925D03*
X1119000Y189500D03*
X1111100Y163749D03*
X1123500Y187000D03*
X1108000Y172000D03*
X1113368Y171619D03*
X1110800Y170000D03*
X1113129Y165719D03*
X1114500Y188700D03*
X1120200Y176500D03*
Y166500D03*
X1129000D03*
Y176500D03*
X1108821Y166800D03*
X1125918Y195418D03*
X1129068Y195500D03*
X1133000Y198000D03*
X1117206Y231741D03*
X1117290Y224241D03*
X1106189D03*
X1106106Y231741D03*
X1120498Y575739D03*
X1154582Y3004D03*
X1134582D03*
X1141500Y124425D03*
Y120500D03*
Y134575D03*
X1158200Y137700D03*
X1136300Y161100D03*
X1140000D03*
X1152781Y165719D03*
X1136300Y172300D03*
X1140000D03*
X1140336Y183560D03*
X1143490D03*
X1152500Y186500D03*
X1158000Y179000D03*
X1140498Y575739D03*
X1160498D03*
X1174582Y3004D03*
X1183021Y165952D03*
X1185521D03*
X1188600Y166000D03*
X1188618Y162782D03*
X1185521Y162952D03*
X1183021D03*
X1180521D03*
Y165952D03*
X1177521D03*
Y162952D03*
X1167600Y184500D03*
Y180500D03*
X1174500Y214000D03*
Y211000D03*
Y208000D03*
Y205000D03*
X1171500D03*
Y208000D03*
Y211000D03*
Y214000D03*
X1179651Y305942D03*
Y309942D03*
X1165070Y328750D03*
X1193411D03*
X1179411Y334250D03*
Y337750D03*
Y330750D03*
Y327250D03*
X1180986Y349234D03*
X1177836D03*
X1179877Y452442D03*
Y448442D03*
X1165190Y471250D03*
X1179500Y476750D03*
Y480250D03*
Y469750D03*
Y473250D03*
X1181075Y491734D03*
X1177925D03*
X1180498Y575739D03*
X1214582Y3004D03*
X1194582D03*
X1193840Y471250D03*
X1200498Y575739D03*
X1220498D03*
X1234582Y3004D03*
X1240498Y575739D03*
X1277657Y4128D03*
X1254582Y3004D03*
X1260498Y575739D03*
X1279438Y573806D03*
X1286766Y12634D03*
X1288331Y30962D03*
Y70962D03*
Y50962D03*
Y90962D03*
Y130962D03*
Y110962D03*
Y150962D03*
Y190962D03*
Y170962D03*
Y210962D03*
Y230962D03*
Y270962D03*
Y250962D03*
Y290962D03*
Y330962D03*
Y310962D03*
Y350962D03*
Y390962D03*
Y370962D03*
Y410962D03*
Y450962D03*
Y430962D03*
Y470962D03*
Y510962D03*
Y490962D03*
Y530962D03*
X1287616Y563889D03*
X1288331Y550962D03*
G54D42*
X860237Y47244D03*
X943225Y228000D03*
X985225Y542500D03*
G54D12*
X72836Y47244D03*
Y535433D03*
X466536Y47244D03*
X860237D03*
X943225Y228000D03*
X985225Y542500D03*
G54D31*
X268000Y220315D03*
X312500D03*
X357000D03*
X428500D03*
X472500D03*
X516500D03*
X578500D03*
X622500D03*
X666500D03*
X735981D03*
X779981D03*
X823981D03*
G54D26*
X185224Y539000D03*
X233224D03*
X281224D03*
X342704D03*
X390704D03*
X438704D03*
X500185D03*
X548185D03*
X596185D03*
X657666D03*
X705666D03*
X753666D03*
G54D16*
X33780Y334724D03*
Y314724D03*
X38780Y319724D03*
Y329724D03*
Y339724D03*
X33780Y344724D03*
X38780Y349724D03*
X48780Y319724D03*
Y329724D03*
Y339724D03*
X43780Y314724D03*
Y324724D03*
Y334724D03*
X48780Y349724D03*
X43780Y344724D03*
G54D20*
X123000Y414500D03*
X119500D03*
Y411500D03*
X123000D03*
X119500Y408500D03*
X123000D03*
X119500Y417500D03*
X123000D03*
X119500Y420500D03*
X123000D03*
X115700Y420600D03*
Y417600D03*
Y408600D03*
Y411600D03*
Y414600D03*
X123000Y426600D03*
X119500D03*
X123000Y423600D03*
X119500D03*
X115700Y423700D03*
Y426700D03*
X168939Y498000D03*
X171939D03*
X216939D03*
X219939D03*
X264939D03*
X267939D03*
X326419D03*
X329419D03*
X374419D03*
X377419D03*
X422419D03*
X425419D03*
X483900D03*
X486900D03*
X531900D03*
X534900D03*
X582900D03*
X579900D03*
X644381D03*
X641381D03*
X692381D03*
X689381D03*
X740381D03*
X737381D03*
X826000Y270525D03*
X911776Y507184D03*
Y510184D03*
Y501184D03*
Y504184D03*
X923595Y498461D03*
X920595D03*
X920542Y504184D03*
X923542D03*
X920542Y501184D03*
X923542D03*
Y510184D03*
X920542D03*
X923542Y507184D03*
X920542D03*
Y513184D03*
X923542D03*
X911829Y498461D03*
X914829D03*
X917595D03*
X917542Y504184D03*
Y501184D03*
Y510184D03*
Y507184D03*
Y513184D03*
X914776D03*
Y507184D03*
Y510184D03*
Y501184D03*
Y504184D03*
X911776Y513184D03*
X920542Y516184D03*
X923542D03*
X917542D03*
X914776D03*
X911776D03*
X917596Y519014D03*
X914830D03*
X911830D03*
X923596D03*
X920596D03*
X1159710Y306037D03*
X1156710D03*
X1159710Y303037D03*
X1156710D03*
X1159710Y300037D03*
X1156710D03*
X1159710Y297037D03*
X1156710D03*
Y294037D03*
X1159710D03*
Y309037D03*
X1156710D03*
X1159710Y312037D03*
X1156710D03*
X1159710Y321037D03*
X1156710D03*
X1159710Y318037D03*
X1156710D03*
X1159710Y315037D03*
X1156710D03*
X1159799Y448537D03*
X1156799D03*
X1159799Y445537D03*
X1156799D03*
X1159799Y442537D03*
X1156799D03*
X1159799Y439537D03*
X1156799D03*
Y436537D03*
X1159799D03*
Y454537D03*
X1156799D03*
X1159799Y451537D03*
X1156799D03*
X1159799Y457537D03*
X1156799D03*
X1159799Y463537D03*
X1156799D03*
X1159799Y460537D03*
X1156799D03*
X1162710Y306037D03*
Y303037D03*
Y300037D03*
Y297037D03*
Y294037D03*
Y309037D03*
Y312037D03*
Y321037D03*
Y318037D03*
Y315037D03*
X1162799Y448537D03*
Y445537D03*
Y442537D03*
Y439537D03*
Y436537D03*
Y454537D03*
Y451537D03*
Y457537D03*
Y463537D03*
Y460537D03*
G54D27*
X185260Y205350D03*
Y208350D03*
X799655Y474684D03*
Y480503D03*
Y477684D03*
X802655Y474684D03*
Y480503D03*
Y477684D03*
X805655Y474684D03*
Y480503D03*
Y477684D03*
X802655Y483503D03*
X805709Y486332D03*
X805655Y483503D03*
X796655Y474684D03*
Y480503D03*
Y477684D03*
X796709Y486332D03*
X796655Y483503D03*
X799709Y486332D03*
X799655Y483503D03*
X802709Y486332D03*
X831000Y270500D03*
X808500Y276075D03*
X836000Y270500D03*
X817709Y486332D03*
X817655Y483503D03*
X808655Y474684D03*
Y480503D03*
Y477684D03*
X811655Y474684D03*
Y480503D03*
Y477684D03*
X814655D03*
Y480503D03*
Y474684D03*
X808709Y486332D03*
X808655Y483503D03*
X811709Y486332D03*
X811655Y483503D03*
X814655D03*
X814709Y486332D03*
X817655Y474684D03*
Y480503D03*
Y477684D03*
X841000Y270500D03*
X856257Y474684D03*
Y480503D03*
Y477684D03*
X859257Y474684D03*
Y480503D03*
Y477684D03*
X862257Y474684D03*
Y480503D03*
Y477684D03*
X859257Y483503D03*
X862311Y486332D03*
X862257Y483503D03*
X853257Y474684D03*
Y480503D03*
Y477684D03*
X853311Y486332D03*
X853257Y483503D03*
X856311Y486332D03*
X856257Y483503D03*
X859311Y486332D03*
X1070400Y123200D03*
X1067600D03*
X1111452Y544000D03*
Y541000D03*
X1114452Y544000D03*
Y541000D03*
Y538000D03*
X1111452D03*
X1120669Y544000D03*
Y541000D03*
X1123669Y544000D03*
Y541000D03*
Y538000D03*
X1120669D03*
X1114452Y553000D03*
X1111452D03*
X1114452Y550000D03*
X1111452D03*
X1114452Y547000D03*
X1111452D03*
X1123669Y553000D03*
X1120669D03*
X1123669Y550000D03*
X1120669D03*
X1123669Y547000D03*
X1120669D03*
G54D28*
X208071Y267204D03*
X200197D03*
X215945D03*
X231693D03*
X223819D03*
X239567D03*
X247441D03*
X357677D03*
X365551D03*
X373425D03*
X389173D03*
X381299D03*
X404921D03*
X397047D03*
X523032D03*
X515158D03*
X530906D03*
X538780D03*
X546654D03*
X562402D03*
X554528D03*
X680513D03*
X672639D03*
X688387D03*
X704135D03*
X696261D03*
X712009D03*
X719883D03*
G54D29*
X193819Y477204D03*
X223819D03*
X351299D03*
X381299D03*
X508780D03*
X538780D03*
X666261D03*
X696261D03*
G54D35*
X296752Y129685D03*
Y139685D03*
Y149685D03*
Y159685D03*
X331752Y129685D03*
X306752D03*
X331752Y139685D03*
Y149685D03*
Y159685D03*
X306752Y139685D03*
Y149685D03*
Y159685D03*
X341752Y129685D03*
Y139685D03*
Y149685D03*
Y159685D03*
X376752Y129685D03*
X366752D03*
X376752Y139685D03*
Y149685D03*
Y159685D03*
X366752Y139685D03*
Y149685D03*
Y159685D03*
X812559Y119408D03*
Y129408D03*
X822559Y119408D03*
Y129408D03*
X832559Y119408D03*
Y129408D03*
X812559Y139408D03*
Y149408D03*
X822559Y139408D03*
Y149408D03*
X832559Y139408D03*
Y149408D03*
X1226024Y286929D03*
X1236024D03*
X1246024D03*
X1256024D03*
G54D43*
X1011000Y98000D03*
Y118000D03*
X1161000Y90400D03*
X1151000D03*
X1171000D03*
G54D40*
X766498Y602542D03*
X766604Y630687D03*
X766498Y612542D03*
X766604Y640687D03*
X1082833Y602542D03*
Y612542D03*
Y630687D03*
Y640687D03*
G54D36*
X411752Y129685D03*
X401752D03*
X411752Y139685D03*
Y149685D03*
Y159685D03*
X401752Y139685D03*
Y149685D03*
Y159685D03*
X446752Y129685D03*
X436752D03*
X446752Y139685D03*
Y149685D03*
Y159685D03*
X436752Y139685D03*
Y149685D03*
Y159685D03*
X481752Y129685D03*
X471752D03*
X481752Y139685D03*
Y149685D03*
Y159685D03*
X471752Y139685D03*
Y149685D03*
Y159685D03*
X1226024Y221929D03*
X1236024D03*
X1246024D03*
X1226024Y231929D03*
X1236024D03*
X1246024D03*
X1226024Y256929D03*
X1236024D03*
X1246024D03*
X1226024Y266929D03*
X1236024D03*
X1246024D03*
X1226024Y306929D03*
X1236024D03*
X1246024D03*
X1226024Y316929D03*
X1236024D03*
X1246024D03*
X1226024Y341929D03*
X1236024D03*
X1246024D03*
X1226024Y351929D03*
X1236024D03*
X1246024D03*
X1256024Y221929D03*
Y231929D03*
Y256929D03*
Y266929D03*
Y306929D03*
Y316929D03*
Y341929D03*
Y351929D03*
G54D33*
X253819Y277204D03*
X268819D03*
G54D44*
X1011000Y108000D03*
G54D25*
X165539Y539000D03*
X213539D03*
X261539D03*
X323019D03*
X371019D03*
X419019D03*
X480500D03*
X528500D03*
X576500D03*
X637981D03*
X685981D03*
X733981D03*
G54D46*
X1096017Y635687D03*
G54D45*
Y607542D03*
G54D24*
X178819Y277204D03*
X193819D03*
X336299D03*
X351299D03*
X411299D03*
X426299D03*
X493780D03*
X508780D03*
X568780D03*
X583780D03*
X651261D03*
X666261D03*
X726261D03*
X741261D03*
G54D13*
X118111Y47244D03*
Y535433D03*
X511811Y47244D03*
G54D11*
X19685Y-614173D03*
Y636929D03*
X619685D03*
X1271654Y-614173D03*
Y636929D03*
G54D14*
X19922Y214173D03*
Y367716D03*
G54D22*
X175000Y100500D03*
X877510Y558620D03*
X964460Y16950D03*
G54D19*
X82795Y99724D03*
Y482205D03*
G54D30*
X249252Y129685D03*
X529252D03*
X665059Y149408D03*
X980059D03*
X1226024Y174429D03*
Y399429D03*
G54D18*
X60630Y99724D03*
Y482205D03*
X108858Y99724D03*
Y482205D03*
G54D23*
X182260Y197050D03*
X179460D03*
X176560D03*
X174660Y205850D03*
Y202650D03*
X167660Y213050D03*
X164760D03*
X167660Y209850D03*
X164760D03*
X805323Y408150D03*
Y405150D03*
X799323D03*
Y408150D03*
X802323Y405150D03*
Y408150D03*
X796600Y408097D03*
Y405097D03*
X802323Y416916D03*
X799323D03*
X805323D03*
X802323Y413916D03*
X799323D03*
X805323D03*
Y411150D03*
X799323D03*
X802323D03*
X796600Y411097D03*
Y413863D03*
Y416863D03*
X811323Y405150D03*
Y408150D03*
X808323D03*
Y405150D03*
Y416916D03*
X811323D03*
X808323Y413916D03*
X811323D03*
Y411150D03*
X808323D03*
X817153Y408096D03*
Y405096D03*
X814323Y405150D03*
Y408150D03*
Y416916D03*
X817153Y416862D03*
X814323Y413916D03*
X817153Y413862D03*
Y411096D03*
X814323Y411150D03*
X850390Y385878D03*
X847390D03*
X859253D03*
X856253D03*
X865542Y385771D03*
X859342Y413916D03*
X856342D03*
X865342D03*
X862342D03*
Y411150D03*
X865342D03*
X856342D03*
X859342D03*
X853619Y411097D03*
Y413863D03*
Y416863D03*
X862342Y408150D03*
Y405150D03*
X865342Y408150D03*
Y405150D03*
X856342D03*
Y408150D03*
X859342Y405150D03*
Y408150D03*
X853619Y408097D03*
Y405097D03*
X859342Y416916D03*
X856342D03*
X865342D03*
X862342D03*
X893091Y385771D03*
X874405D03*
X877405D03*
X868542D03*
X884228D03*
X887228D03*
X868342Y416916D03*
X871342D03*
X868342Y413916D03*
X871342D03*
Y411150D03*
X868342D03*
X874172Y408096D03*
Y405096D03*
Y416862D03*
Y413862D03*
Y411096D03*
X871342Y405150D03*
Y408150D03*
X868342Y405150D03*
Y408150D03*
X896091Y385771D03*
X912525Y385877D03*
X906662D03*
X903662D03*
X922454Y385771D03*
X915525Y385877D03*
X925454Y385771D03*
X944247Y385877D03*
X941247D03*
X931317Y385771D03*
X934317D03*
X950110Y385877D03*
X953110D03*
X1066500Y538000D03*
Y541000D03*
X1069500D03*
X1066500Y544000D03*
X1069500D03*
Y538000D03*
Y547000D03*
Y550000D03*
X1066500Y547000D03*
Y550000D03*
Y553000D03*
X1069500D03*
X1097100Y35582D03*
Y38582D03*
X1099600D03*
Y35582D03*
X1102100D03*
Y38582D03*
X1096961Y18126D03*
Y21126D03*
X1099461D03*
Y18126D03*
X1101961D03*
Y21126D03*
X1097101Y53737D03*
Y56737D03*
X1099601D03*
Y53737D03*
X1102101D03*
Y56737D03*
X1125170Y35582D03*
Y38582D03*
X1127670D03*
Y35582D03*
X1130170D03*
Y38582D03*
X1104600Y35582D03*
Y38582D03*
X1107100Y35582D03*
Y38582D03*
X1104461Y18126D03*
Y21126D03*
X1106961Y18126D03*
Y21126D03*
X1130031D03*
Y18126D03*
X1127531D03*
Y21126D03*
X1125031D03*
Y18126D03*
X1104601Y53737D03*
Y56737D03*
X1107101Y53737D03*
Y56737D03*
X1132670Y35582D03*
X1135170D03*
Y38582D03*
X1132670D03*
X1135031Y21126D03*
Y18126D03*
X1132531Y21126D03*
Y18126D03*
X1132950Y82867D03*
Y85867D03*
X1135450D03*
Y82867D03*
X1137950D03*
X1140450D03*
X1142950D03*
Y85867D03*
X1140450D03*
X1137950D03*
X1183321Y123652D03*
X1185821D03*
X1188321D03*
Y120652D03*
X1185821D03*
X1183321D03*
X1180821D03*
Y123652D03*
X1178321D03*
Y120652D03*
G54D21*
X140400Y258360D03*
X143400D03*
X140400Y261360D03*
X143400D03*
X140400Y255360D03*
X143400D03*
X165350Y220098D03*
X162850D03*
Y227185D03*
Y230728D03*
X165350Y223642D03*
Y227185D03*
Y230728D03*
X162850Y223642D03*
X157000Y414500D03*
X160500D03*
Y417500D03*
X157000D03*
X160500Y420500D03*
X157000D03*
X160500Y411500D03*
X157000D03*
X160500Y408500D03*
X157000D03*
X164000Y414600D03*
Y417600D03*
Y420600D03*
Y411600D03*
Y408600D03*
X160300Y423600D03*
X156800D03*
X160300Y426600D03*
X156800D03*
X163800Y426700D03*
Y423700D03*
X171939Y518000D03*
X168939D03*
X194160Y205200D03*
Y208200D03*
X200160Y205200D03*
Y208200D03*
X197160Y205200D03*
Y208200D03*
X218500Y309500D03*
X226975D03*
X235975D03*
X219939Y518000D03*
X216939D03*
X267939D03*
X264939D03*
X283000Y203500D03*
Y198500D03*
Y196000D03*
Y206000D03*
X285219Y279078D03*
X281219D03*
X277219D03*
X285219Y275078D03*
X281219D03*
X277219D03*
X285219Y271078D03*
X281219D03*
X277219D03*
Y283078D03*
X281219D03*
X285219D03*
X326000Y203500D03*
Y198500D03*
Y196000D03*
Y206000D03*
X304500Y203500D03*
Y198500D03*
Y196000D03*
Y206000D03*
X329419Y518000D03*
X326419D03*
X347500Y203500D03*
Y198500D03*
Y196000D03*
Y206000D03*
X361000Y305975D03*
X390500Y203500D03*
Y198500D03*
Y196000D03*
Y206000D03*
X369000Y203500D03*
Y198500D03*
Y196000D03*
Y206000D03*
X375500Y309500D03*
X383975D03*
X377419Y518000D03*
X374419D03*
X412000Y203500D03*
Y198500D03*
Y196000D03*
Y206000D03*
X392975Y309500D03*
X425419Y518000D03*
X422419D03*
X486900D03*
X483900D03*
X533475Y310500D03*
X534900Y518000D03*
X531900D03*
X542475Y310500D03*
X551475D03*
X562000Y442000D03*
X564500D03*
X590500Y203000D03*
Y198000D03*
Y195500D03*
Y205500D03*
X582900Y518000D03*
X579900D03*
X612000Y203000D03*
Y198000D03*
Y195500D03*
Y205500D03*
X655000Y203000D03*
Y198000D03*
Y195500D03*
Y205500D03*
X633500Y203000D03*
Y198000D03*
Y195500D03*
Y205500D03*
X644381Y518000D03*
X641381D03*
X676500Y195500D03*
Y198000D03*
Y203000D03*
Y205500D03*
X697990Y195500D03*
Y198000D03*
Y203000D03*
Y205500D03*
X690956Y310500D03*
X699956D03*
X708956D03*
X692381Y518000D03*
X689381D03*
X747160Y30000D03*
Y38500D03*
Y64000D03*
Y47000D03*
Y55500D03*
X719490Y195500D03*
Y198000D03*
Y203000D03*
Y205500D03*
X742500Y328500D03*
Y324500D03*
Y334500D03*
X742000Y341500D03*
X742500Y347700D03*
Y353200D03*
X740381Y518000D03*
X737381D03*
X750300Y27200D03*
X752560Y30100D03*
X749760D03*
X752560Y38600D03*
X749760D03*
X752560Y64100D03*
X749760D03*
X752560Y47100D03*
X749760D03*
X752560Y55600D03*
X749760D03*
X803900Y279425D03*
X800575Y338000D03*
X803000Y357000D03*
Y346500D03*
X811500Y329000D03*
X815500D03*
X823500D03*
X829500Y354925D03*
X811575Y344000D03*
X846000Y270525D03*
X851000D03*
X856000D03*
X839692Y329592D03*
X854825Y330925D03*
X849000Y399000D03*
X865311Y486332D03*
X865257Y483503D03*
Y474684D03*
Y480503D03*
Y477684D03*
X854082Y505410D03*
X848263D03*
X851082D03*
X854082Y508410D03*
X848263D03*
X851082D03*
X854082Y511410D03*
X848263D03*
X851082D03*
X854082Y514410D03*
X848263D03*
X851082D03*
X845263Y508410D03*
X842434Y511464D03*
X845263Y511410D03*
X842434Y514464D03*
X845263Y514410D03*
X854082Y502410D03*
X848263D03*
X851082D03*
X842434Y502464D03*
X845263Y502410D03*
X842434Y505464D03*
X845263Y505410D03*
X842434Y508464D03*
Y523464D03*
X845263Y523410D03*
X854082Y517410D03*
X848263D03*
X851082D03*
Y520410D03*
X848263D03*
X854082D03*
X842434Y517464D03*
X845263Y517410D03*
Y520410D03*
X842434Y520464D03*
X854082Y523410D03*
X848263D03*
X851082D03*
X868311Y486332D03*
X868257Y483503D03*
Y477684D03*
Y480503D03*
Y474684D03*
X871311Y486332D03*
X874311D03*
X874257Y477684D03*
Y480503D03*
Y474684D03*
X871257Y483503D03*
Y474684D03*
Y480503D03*
Y477684D03*
X874257Y483503D03*
X1068900Y110000D03*
X1060000Y249000D03*
X1063000D03*
X1066000D03*
Y246000D03*
X1063000D03*
X1060000D03*
X1066000Y243000D03*
X1063000D03*
X1060000D03*
X1069000Y246000D03*
Y243000D03*
X1072000Y246000D03*
Y243000D03*
X1060000Y252000D03*
X1063000D03*
X1066000D03*
Y258000D03*
X1063000D03*
X1060000D03*
X1066000Y255000D03*
X1063000D03*
X1060000D03*
X1069000Y258000D03*
Y255000D03*
X1072000Y258000D03*
Y255000D03*
X1060000Y296500D03*
X1063000D03*
X1066000D03*
Y293500D03*
X1063000D03*
X1060000D03*
X1069000D03*
X1060000Y299500D03*
X1063000D03*
X1066000D03*
Y305500D03*
X1063000D03*
X1060000D03*
X1066000Y302500D03*
X1063000D03*
X1060000D03*
X1069000Y305500D03*
Y302500D03*
X1066000Y290500D03*
X1063000D03*
X1060000D03*
X1069000D03*
X1072000Y293500D03*
Y305500D03*
Y302500D03*
Y290500D03*
X1066000Y338000D03*
X1063000D03*
X1060000D03*
X1069000D03*
X1072000D03*
X1060000Y344000D03*
X1063000D03*
X1066000D03*
X1060000Y347000D03*
X1063000D03*
X1066000D03*
Y341000D03*
X1063000D03*
X1060000D03*
X1066000Y353000D03*
X1063000D03*
X1060000D03*
X1066000Y350000D03*
X1063000D03*
X1060000D03*
X1069000Y353000D03*
Y350000D03*
Y341000D03*
X1072000Y353000D03*
Y350000D03*
Y341000D03*
X1066000Y397500D03*
X1063000D03*
X1060000D03*
X1069000D03*
X1060000Y391500D03*
X1063000D03*
X1066000D03*
X1060000Y394500D03*
X1063000D03*
X1066000D03*
Y388500D03*
X1063000D03*
X1060000D03*
X1066000Y385500D03*
X1063000D03*
X1060000D03*
X1069000Y388500D03*
Y385500D03*
X1072000Y397500D03*
Y388500D03*
Y385500D03*
X1066000Y400500D03*
X1063000D03*
X1060000D03*
X1069000D03*
X1072000D03*
X1066000Y433000D03*
X1063000D03*
X1060000D03*
X1069000D03*
X1060000Y439000D03*
X1063000D03*
X1066000D03*
X1060000Y442000D03*
X1063000D03*
X1066000D03*
Y436000D03*
X1063000D03*
X1060000D03*
X1069000D03*
X1072000Y433000D03*
Y436000D03*
X1066000Y448000D03*
X1063000D03*
X1060000D03*
X1066000Y445000D03*
X1063000D03*
X1060000D03*
X1069000Y448000D03*
Y445000D03*
X1072000Y448000D03*
Y445000D03*
X1069000Y480500D03*
Y483500D03*
X1060000Y480500D03*
X1063000D03*
X1066000D03*
X1060000Y483500D03*
X1063000D03*
X1066000D03*
Y486500D03*
X1063000D03*
X1060000D03*
X1072000Y480500D03*
Y483500D03*
X1069000Y492500D03*
Y495500D03*
X1060000Y492500D03*
X1063000D03*
X1066000D03*
X1060000Y495500D03*
X1063000D03*
X1066000D03*
Y489500D03*
X1063000D03*
X1060000D03*
X1072000Y492500D03*
Y495500D03*
X1091000Y99500D03*
X1095100D03*
X1073200Y126000D03*
Y128800D03*
Y123200D03*
X1084740Y108000D03*
X1094493Y151856D03*
X1087500Y198000D03*
Y201000D03*
X1101903Y285019D03*
X1101796Y331894D03*
X1113000Y101240D03*
X1119500Y86000D03*
Y83000D03*
X1123000Y120816D03*
X1126000D03*
X1131500D03*
X1108500Y136500D03*
X1118774Y284699D03*
X1112902D03*
X1110019Y284806D03*
X1104786Y284912D03*
X1121657Y284592D03*
X1118667Y331574D03*
X1112795D03*
X1109912Y331681D03*
X1104679Y331787D03*
X1121550Y331467D03*
X1104009Y427245D03*
X1120880Y426925D03*
X1115008D03*
X1112125Y427032D03*
X1106892Y427138D03*
X1123763Y426818D03*
X1103800Y474339D03*
X1106683Y474232D03*
X1111916Y474126D03*
X1114799Y474019D03*
X1120671D03*
X1123554Y473912D03*
X1155000Y124913D03*
X1159300Y129700D03*
X1134500Y120816D03*
X1154000Y151500D03*
X1160200Y175982D03*
X1138203Y266860D03*
Y260860D03*
Y263860D03*
X1135203Y260860D03*
Y263860D03*
Y266860D03*
X1138203Y257860D03*
Y254860D03*
X1135203Y257860D03*
Y254860D03*
X1135403Y302360D03*
Y305360D03*
X1138403Y302360D03*
Y305360D03*
X1135403Y308360D03*
X1138403D03*
X1135403Y314360D03*
Y311360D03*
X1138403D03*
Y314360D03*
Y361979D03*
X1135403D03*
X1138403Y358979D03*
X1135403D03*
X1138403Y355979D03*
X1135403D03*
X1138403Y352979D03*
X1135403D03*
X1138403Y349979D03*
X1135403D03*
X1135190Y396965D03*
X1138190D03*
X1135190Y399965D03*
X1138190D03*
X1135190Y402965D03*
Y405965D03*
Y408965D03*
X1138190Y402965D03*
Y405965D03*
Y408965D03*
X1135404Y457228D03*
Y454228D03*
Y451228D03*
Y445228D03*
Y448228D03*
X1138404Y454228D03*
Y451228D03*
Y445228D03*
Y448228D03*
Y457228D03*
X1135622Y485732D03*
Y470732D03*
Y467732D03*
Y479732D03*
Y476732D03*
Y473732D03*
Y482732D03*
X1138622D03*
Y473732D03*
Y476732D03*
Y479732D03*
Y470732D03*
Y485732D03*
Y467732D03*
X1177475Y111500D03*
X1179500Y105500D03*
X1162700Y175959D03*
X1203887Y306894D03*
X1200887D03*
X1197887D03*
X1203887Y303894D03*
X1200887D03*
X1197887D03*
X1203887Y300894D03*
X1200887D03*
X1197887D03*
X1203887Y297894D03*
X1200887D03*
X1197887D03*
X1203887Y294894D03*
X1200887D03*
X1197887D03*
Y321894D03*
X1200887D03*
X1203887D03*
Y318894D03*
X1200887D03*
X1197887D03*
X1203887Y315894D03*
X1200887D03*
X1197887D03*
X1203887Y312894D03*
X1200887D03*
X1197887D03*
X1203887Y309894D03*
X1200887D03*
X1197887D03*
X1197976Y437394D03*
X1200976D03*
X1203976D03*
X1197976Y440394D03*
X1200976D03*
X1203976D03*
X1197976Y443394D03*
X1200976D03*
X1203976D03*
X1197976Y446394D03*
X1200976D03*
X1203976D03*
X1197976Y449394D03*
X1200976D03*
X1203976D03*
X1197976Y452394D03*
X1200976D03*
X1203976D03*
X1197976Y455394D03*
X1200976D03*
X1203976D03*
X1197976Y464394D03*
X1200976D03*
X1203976D03*
X1197976Y458394D03*
X1200976D03*
X1203976D03*
X1197976Y461394D03*
X1200976D03*
X1203976D03*
G54D37*
X712559Y129408D03*
Y119408D03*
Y149408D03*
Y139408D03*
X722559Y129408D03*
Y119408D03*
X747559Y129408D03*
Y119408D03*
X722559Y149408D03*
Y139408D03*
X747559Y149408D03*
Y139408D03*
X757559Y129408D03*
Y119408D03*
Y149408D03*
Y139408D03*
X782559Y129408D03*
Y119408D03*
X792559Y129408D03*
Y119408D03*
X782559Y149408D03*
Y139408D03*
X792559Y149408D03*
Y139408D03*
X852559Y129408D03*
Y119408D03*
X862559Y129408D03*
Y119408D03*
X852559Y149408D03*
Y139408D03*
X862559Y149408D03*
Y139408D03*
X887559Y129408D03*
Y119408D03*
Y149408D03*
Y139408D03*
X897559Y129408D03*
Y119408D03*
X922559Y129408D03*
Y119408D03*
X897559Y149408D03*
Y139408D03*
X922559Y149408D03*
Y139408D03*
X932559Y129408D03*
Y119408D03*
Y149408D03*
Y139408D03*
G54D48*
X1226024Y174429D03*
Y399429D03*
G54D17*
X33780Y324724D03*
G54D32*
X268000Y240000D03*
X312500D03*
X357000D03*
X428500D03*
X472500D03*
X516500D03*
X578500D03*
X622500D03*
X666500D03*
X735981D03*
X779981D03*
X823981D03*
G54D15*
X38780Y232598D03*
Y239291D03*
Y252598D03*
Y259291D03*
Y272598D03*
Y279291D03*
Y292598D03*
Y299291D03*
X48780Y232598D03*
Y239291D03*
Y252598D03*
Y259291D03*
Y272598D03*
Y279291D03*
Y292598D03*
Y299291D03*
G54D47*
X1240158Y57480D03*
Y521260D03*
G54D34*
X253819Y477204D03*
X411299D03*
X568780D03*
X726261D03*
G54D39*
X753314Y607542D03*
G54D41*
X753420Y635687D03*
%LPC*%
G75*
G54D50*
G01X-297025Y-1013390D02*
Y1828909D01*
X3691357D01*
Y-1013390D01*
X-297025D01*
G01X4093Y-769672D02*
Y-844672D01*
X504093D01*
Y-769672D01*
X4093D01*
G01X16093Y-834672D02*
Y-839672D01*
G01X14636Y-834672D02*
X17550D01*
G01X22460Y-839672D02*
X19926D01*
Y-834672D01*
X22460D01*
G01X21446Y-837089D02*
X19926D01*
G01X25026Y-834672D02*
Y-839672D01*
X27560D01*
G01X31393Y-839839D02*
X31266Y-839755D01*
Y-839589D01*
X31393Y-839505D01*
X31520Y-839589D01*
Y-839755D01*
X31393Y-839839D01*
G01Y-837589D02*
X31266Y-837505D01*
Y-837339D01*
X31393Y-837255D01*
X31520Y-837339D01*
Y-837505D01*
X31393Y-837589D01*
G01X36176Y-841339D02*
X35543Y-840505D01*
X35226Y-839672D01*
Y-836339D01*
X35543Y-835505D01*
X36176Y-834672D01*
G01X41593D02*
X41086Y-834839D01*
X40706Y-835255D01*
X40453Y-835755D01*
X40263Y-836422D01*
X40200Y-837172D01*
X40263Y-837922D01*
X40453Y-838589D01*
X40706Y-839089D01*
X41086Y-839505D01*
X41593Y-839672D01*
X42100Y-839505D01*
X42480Y-839089D01*
X42733Y-838589D01*
X42923Y-837922D01*
X42986Y-837172D01*
X42923Y-836422D01*
X42733Y-835755D01*
X42480Y-835255D01*
X42100Y-834839D01*
X41593Y-834672D01*
G01X45300Y-838672D02*
X45680Y-839255D01*
X46186Y-839589D01*
X46756Y-839672D01*
X47263Y-839589D01*
X47770Y-839172D01*
X48086Y-838672D01*
X48150Y-838172D01*
X48023Y-837589D01*
X47580Y-837172D01*
X47136Y-837005D01*
X46566D01*
G01X47136D02*
X47516Y-836755D01*
X47833Y-836339D01*
X47960Y-835839D01*
X47833Y-835339D01*
X47516Y-834922D01*
X46946Y-834672D01*
X46376Y-834755D01*
X45806Y-835089D01*
G01X52110Y-841339D02*
X52743Y-840505D01*
X53060Y-839672D01*
Y-836339D01*
X52743Y-835505D01*
X52110Y-834672D01*
G01X55500Y-838672D02*
X55880Y-839255D01*
X56386Y-839589D01*
X56956Y-839672D01*
X57463Y-839589D01*
X57970Y-839172D01*
X58286Y-838672D01*
X58350Y-838172D01*
X58223Y-837589D01*
X57780Y-837172D01*
X57336Y-837005D01*
X56766D01*
G01X57336D02*
X57716Y-836755D01*
X58033Y-836339D01*
X58160Y-835839D01*
X58033Y-835339D01*
X57716Y-834922D01*
X57146Y-834672D01*
X56576Y-834755D01*
X56006Y-835089D01*
G01X60790Y-835505D02*
X61170Y-835005D01*
X61613Y-834755D01*
X62120Y-834672D01*
X62753Y-834839D01*
X63196Y-835255D01*
X63323Y-835755D01*
X63260Y-836255D01*
X63006Y-836672D01*
X61740Y-837505D01*
X61170Y-838089D01*
X60790Y-838922D01*
X60663Y-839672D01*
X63323D01*
G01X66966D02*
X67093Y-838589D01*
X67283Y-837672D01*
X67536Y-836839D01*
X67853Y-835922D01*
X68360Y-834672D01*
X65826D01*
G01X71370Y-838005D02*
X73016D01*
G01X76090Y-835505D02*
X76470Y-835005D01*
X76913Y-834755D01*
X77420Y-834672D01*
X78053Y-834839D01*
X78496Y-835255D01*
X78623Y-835755D01*
X78560Y-836255D01*
X78306Y-836672D01*
X77040Y-837505D01*
X76470Y-838089D01*
X76090Y-838922D01*
X75963Y-839672D01*
X78623D01*
G01X81000Y-838672D02*
X81380Y-839255D01*
X81886Y-839589D01*
X82456Y-839672D01*
X82963Y-839589D01*
X83470Y-839172D01*
X83786Y-838672D01*
X83850Y-838172D01*
X83723Y-837589D01*
X83280Y-837172D01*
X82836Y-837005D01*
X82266D01*
G01X82836D02*
X83216Y-836755D01*
X83533Y-836339D01*
X83660Y-835839D01*
X83533Y-835339D01*
X83216Y-834922D01*
X82646Y-834672D01*
X82076Y-834755D01*
X81506Y-835089D01*
G01X88253Y-839672D02*
Y-834672D01*
X85910Y-838255D01*
X89076D01*
G01X91200Y-838922D02*
X91580Y-839339D01*
X92023Y-839589D01*
X92593Y-839672D01*
X93163Y-839505D01*
X93606Y-839172D01*
X93923Y-838589D01*
X93986Y-837922D01*
X93860Y-837255D01*
X93543Y-836839D01*
X93100Y-836505D01*
X92656Y-836422D01*
X92213Y-836505D01*
X91643Y-836839D01*
X91833Y-834672D01*
X93543D01*
G01X101590Y-839672D02*
Y-834672D01*
X103996D01*
G01X103110Y-837089D02*
X101590D01*
G01X106310Y-839672D02*
X107893Y-834672D01*
X109476Y-839672D01*
G01X108906Y-837922D02*
X106880D01*
G01X111663Y-839672D02*
X114323Y-834672D01*
G01X111663D02*
X114323Y-839672D01*
G01X118093Y-839839D02*
X117966Y-839755D01*
Y-839589D01*
X118093Y-839505D01*
X118220Y-839589D01*
Y-839755D01*
X118093Y-839839D01*
G01Y-837589D02*
X117966Y-837505D01*
Y-837339D01*
X118093Y-837255D01*
X118220Y-837339D01*
Y-837505D01*
X118093Y-837589D01*
G01X122876Y-841339D02*
X122243Y-840505D01*
X121926Y-839672D01*
Y-836339D01*
X122243Y-835505D01*
X122876Y-834672D01*
G01X128293D02*
X127786Y-834839D01*
X127406Y-835255D01*
X127153Y-835755D01*
X126963Y-836422D01*
X126900Y-837172D01*
X126963Y-837922D01*
X127153Y-838589D01*
X127406Y-839089D01*
X127786Y-839505D01*
X128293Y-839672D01*
X128800Y-839505D01*
X129180Y-839089D01*
X129433Y-838589D01*
X129623Y-837922D01*
X129686Y-837172D01*
X129623Y-836422D01*
X129433Y-835755D01*
X129180Y-835255D01*
X128800Y-834839D01*
X128293Y-834672D01*
G01X132000Y-838672D02*
X132380Y-839255D01*
X132886Y-839589D01*
X133456Y-839672D01*
X133963Y-839589D01*
X134470Y-839172D01*
X134786Y-838672D01*
X134850Y-838172D01*
X134723Y-837589D01*
X134280Y-837172D01*
X133836Y-837005D01*
X133266D01*
G01X133836D02*
X134216Y-836755D01*
X134533Y-836339D01*
X134660Y-835839D01*
X134533Y-835339D01*
X134216Y-834922D01*
X133646Y-834672D01*
X133076Y-834755D01*
X132506Y-835089D01*
G01X138810Y-841339D02*
X139443Y-840505D01*
X139760Y-839672D01*
Y-836339D01*
X139443Y-835505D01*
X138810Y-834672D01*
G01X142200Y-838672D02*
X142580Y-839255D01*
X143086Y-839589D01*
X143656Y-839672D01*
X144163Y-839589D01*
X144670Y-839172D01*
X144986Y-838672D01*
X145050Y-838172D01*
X144923Y-837589D01*
X144480Y-837172D01*
X144036Y-837005D01*
X143466D01*
G01X144036D02*
X144416Y-836755D01*
X144733Y-836339D01*
X144860Y-835839D01*
X144733Y-835339D01*
X144416Y-834922D01*
X143846Y-834672D01*
X143276Y-834755D01*
X142706Y-835089D01*
G01X147616Y-839089D02*
X148060Y-839505D01*
X148566Y-839672D01*
X149073Y-839505D01*
X149516Y-839005D01*
X149833Y-838255D01*
X149960Y-837505D01*
Y-836589D01*
X149833Y-835839D01*
X149516Y-835172D01*
X149136Y-834839D01*
X148693Y-834672D01*
X148186Y-834839D01*
X147806Y-835172D01*
X147553Y-835672D01*
X147426Y-836339D01*
X147553Y-836922D01*
X147870Y-837505D01*
X148250Y-837839D01*
X148693Y-837922D01*
X149200Y-837755D01*
X149580Y-837339D01*
X149960Y-836589D01*
G01X153666Y-839672D02*
X153793Y-838589D01*
X153983Y-837672D01*
X154236Y-836839D01*
X154553Y-835922D01*
X155060Y-834672D01*
X152526D01*
G01X158070Y-838005D02*
X159716D01*
G01X162600Y-838672D02*
X162980Y-839255D01*
X163486Y-839589D01*
X164056Y-839672D01*
X164563Y-839589D01*
X165070Y-839172D01*
X165386Y-838672D01*
X165450Y-838172D01*
X165323Y-837589D01*
X164880Y-837172D01*
X164436Y-837005D01*
X163866D01*
G01X164436D02*
X164816Y-836755D01*
X165133Y-836339D01*
X165260Y-835839D01*
X165133Y-835339D01*
X164816Y-834922D01*
X164246Y-834672D01*
X163676Y-834755D01*
X163106Y-835089D01*
G01X167890Y-837589D02*
X168333Y-837005D01*
X168713Y-836672D01*
X169220Y-836505D01*
X169663Y-836672D01*
X169980Y-837005D01*
X170233Y-837505D01*
X170296Y-838089D01*
X170233Y-838589D01*
X169980Y-839089D01*
X169600Y-839505D01*
X169156Y-839672D01*
X168650Y-839505D01*
X168206Y-839005D01*
X167953Y-838255D01*
X167890Y-837422D01*
X168016Y-836339D01*
X168206Y-835755D01*
X168523Y-835172D01*
X168966Y-834755D01*
X169410Y-834672D01*
X169853Y-834839D01*
X170170Y-835255D01*
G01X174193Y-839672D02*
Y-834672D01*
X173433Y-835672D01*
G01Y-839672D02*
X174953D01*
G01X180053D02*
Y-834672D01*
X177710Y-838255D01*
X180876D01*
G01X199093Y-769672D02*
Y-844672D01*
G01Y-819672D02*
X302093D01*
Y-794672D01*
G01X199093D02*
X302093D01*
G01X309600Y-829672D02*
Y-824672D01*
X310866D01*
X311373Y-824922D01*
X311753Y-825255D01*
X312070Y-825755D01*
X312323Y-826339D01*
X312386Y-827172D01*
X312323Y-828005D01*
X312070Y-828589D01*
X311753Y-829089D01*
X311373Y-829422D01*
X310866Y-829672D01*
X309600D01*
G01X314510D02*
X316093Y-824672D01*
X317676Y-829672D01*
G01X317106Y-827922D02*
X315080D01*
G01X321193Y-824672D02*
Y-829672D01*
G01X319736Y-824672D02*
X322650D01*
G01X327560Y-829672D02*
X325026D01*
Y-824672D01*
X327560D01*
G01X326546Y-827089D02*
X325026D01*
G01X331393Y-829839D02*
X331266Y-829755D01*
Y-829589D01*
X331393Y-829505D01*
X331520Y-829589D01*
Y-829755D01*
X331393Y-829839D01*
G01Y-827589D02*
X331266Y-827505D01*
Y-827339D01*
X331393Y-827255D01*
X331520Y-827339D01*
Y-827505D01*
X331393Y-827589D01*
G01X304093Y-769672D02*
Y-844672D01*
G01X302093Y-769672D02*
Y-844672D01*
G01X304093Y-819672D02*
X504093D01*
G01X309726Y-804672D02*
Y-799672D01*
X311246D01*
X311753Y-799922D01*
X312133Y-800505D01*
X312260Y-801172D01*
X312133Y-801839D01*
X311816Y-802339D01*
X311246Y-802589D01*
X309726D01*
G01X314953Y-804839D02*
X317233Y-799672D01*
G01X319736Y-804672D02*
Y-799672D01*
X322650Y-804672D01*
Y-799672D01*
G01X326293Y-804839D02*
X326166Y-804755D01*
Y-804589D01*
X326293Y-804505D01*
X326420Y-804589D01*
Y-804755D01*
X326293Y-804839D01*
G01Y-802589D02*
X326166Y-802505D01*
Y-802339D01*
X326293Y-802255D01*
X326420Y-802339D01*
Y-802505D01*
X326293Y-802589D01*
G01X304093Y-794672D02*
X504093D01*
G01X309726Y-779672D02*
Y-774672D01*
X311246D01*
X311753Y-774922D01*
X312133Y-775505D01*
X312260Y-776172D01*
X312133Y-776839D01*
X311816Y-777339D01*
X311246Y-777589D01*
X309726D01*
G01X314826Y-779672D02*
Y-774672D01*
X316410D01*
X316916Y-774922D01*
X317233Y-775255D01*
X317360Y-775922D01*
X317233Y-776589D01*
X316853Y-777005D01*
X316410Y-777255D01*
X314826D01*
G01X316410D02*
X317360Y-779672D01*
G01X321193D02*
X320686Y-779589D01*
X320243Y-779255D01*
X319863Y-778755D01*
X319610Y-778172D01*
X319483Y-777505D01*
Y-776839D01*
X319610Y-776172D01*
X319863Y-775589D01*
X320243Y-775089D01*
X320686Y-774755D01*
X321193Y-774672D01*
X321700Y-774755D01*
X322143Y-775089D01*
X322523Y-775589D01*
X322776Y-776172D01*
X322903Y-776839D01*
Y-777505D01*
X322776Y-778172D01*
X322523Y-778755D01*
X322143Y-779255D01*
X321700Y-779589D01*
X321193Y-779672D01*
G01X325026Y-778672D02*
X325343Y-779172D01*
X325723Y-779505D01*
X326166Y-779672D01*
X326673Y-779505D01*
X327053Y-779172D01*
X327433Y-778672D01*
X327560Y-778005D01*
Y-774672D01*
G01X332660Y-779672D02*
X330126D01*
Y-774672D01*
X332660D01*
G01X331646Y-777089D02*
X330126D01*
G01X337886Y-775089D02*
X337506Y-774839D01*
X337063Y-774672D01*
X336556D01*
X335986Y-774922D01*
X335543Y-775339D01*
X335226Y-775839D01*
X334973Y-776672D01*
X334910Y-777422D01*
X335036Y-778172D01*
X335226Y-778672D01*
X335606Y-779172D01*
X336050Y-779505D01*
X336493Y-779672D01*
X336936D01*
X337380Y-779505D01*
X337760Y-779255D01*
X338076Y-778922D01*
G01X341593Y-774672D02*
Y-779672D01*
G01X340136Y-774672D02*
X343050D01*
G01X346693Y-779839D02*
X346566Y-779755D01*
Y-779589D01*
X346693Y-779505D01*
X346820Y-779589D01*
Y-779755D01*
X346693Y-779839D01*
G01Y-777589D02*
X346566Y-777505D01*
Y-777339D01*
X346693Y-777255D01*
X346820Y-777339D01*
Y-777505D01*
X346693Y-777589D01*
G01X419093Y-819672D02*
Y-844672D01*
G01X421726Y-822172D02*
Y-827172D01*
X424260D01*
G01X427333Y-822172D02*
X428853D01*
G01X428093D02*
Y-827172D01*
G01X427333D02*
X428853D01*
G01X433700Y-824505D02*
X433953Y-824255D01*
X434143Y-823839D01*
X434270Y-823255D01*
X434143Y-822755D01*
X433890Y-822422D01*
X433446Y-822172D01*
X431736D01*
Y-827172D01*
X433826D01*
X434270Y-826839D01*
X434523Y-826339D01*
X434650Y-825755D01*
X434523Y-825172D01*
X434143Y-824672D01*
X433700Y-824505D01*
X431736D01*
G01X438293Y-827339D02*
X438166Y-827255D01*
Y-827089D01*
X438293Y-827005D01*
X438420Y-827089D01*
Y-827255D01*
X438293Y-827339D01*
G01Y-825089D02*
X438166Y-825005D01*
Y-824839D01*
X438293Y-824755D01*
X438420Y-824839D01*
Y-825005D01*
X438293Y-825089D01*
G01X470106Y-847839D02*
X470213Y-847714D01*
X470293Y-847505D01*
X470346Y-847214D01*
X470293Y-846964D01*
X470186Y-846797D01*
X470000Y-846672D01*
X469280D01*
Y-849172D01*
X470160D01*
X470346Y-849005D01*
X470453Y-848755D01*
X470506Y-848464D01*
X470453Y-848172D01*
X470293Y-847922D01*
X470106Y-847839D01*
X469280D01*
G01X472573Y-849172D02*
Y-847505D01*
G01Y-847797D02*
X472466Y-847630D01*
X472306Y-847547D01*
X472120Y-847505D01*
X471933Y-847589D01*
X471773Y-847755D01*
X471666Y-848005D01*
X471613Y-848339D01*
X471666Y-848672D01*
X471773Y-848922D01*
X471933Y-849089D01*
X472120Y-849172D01*
X472306Y-849130D01*
X472466Y-849005D01*
X472573Y-848839D01*
G01X473893Y-848880D02*
X474026Y-849047D01*
X474213Y-849172D01*
X474373D01*
X474533Y-849089D01*
X474640Y-848964D01*
X474693Y-848797D01*
X474666Y-848547D01*
X474560Y-848422D01*
X474080Y-848172D01*
X473973Y-847880D01*
X474026Y-847672D01*
X474133Y-847547D01*
X474293Y-847505D01*
X474453Y-847547D01*
X474613Y-847672D01*
G01X476093Y-848047D02*
X476946D01*
X476866Y-847755D01*
X476733Y-847589D01*
X476546Y-847505D01*
X476360Y-847547D01*
X476200Y-847672D01*
X476093Y-847964D01*
X476040Y-848214D01*
Y-848464D01*
X476093Y-848714D01*
X476226Y-848964D01*
X476386Y-849130D01*
X476573Y-849172D01*
X476760Y-849089D01*
X476946Y-848839D01*
G01X478213Y-849172D02*
Y-846672D01*
G01Y-847922D02*
X478346Y-847672D01*
X478506Y-847547D01*
X478666Y-847505D01*
X478906Y-847589D01*
X479066Y-847755D01*
X479173Y-848047D01*
Y-848380D01*
X479120Y-848714D01*
X479013Y-848964D01*
X478826Y-849130D01*
X478666Y-849172D01*
X478506Y-849130D01*
X478346Y-849005D01*
X478213Y-848797D01*
G01X480893Y-849172D02*
X480733Y-849130D01*
X480573Y-848964D01*
X480466Y-848672D01*
X480413Y-848339D01*
X480466Y-848005D01*
X480573Y-847714D01*
X480733Y-847547D01*
X480893Y-847505D01*
X481053Y-847547D01*
X481213Y-847714D01*
X481320Y-848005D01*
X481346Y-848339D01*
X481320Y-848672D01*
X481213Y-848964D01*
X481053Y-849130D01*
X480893Y-849172D01*
G01X483573D02*
Y-847505D01*
G01Y-847797D02*
X483466Y-847630D01*
X483306Y-847547D01*
X483120Y-847505D01*
X482933Y-847589D01*
X482773Y-847755D01*
X482666Y-848005D01*
X482613Y-848339D01*
X482666Y-848672D01*
X482773Y-848922D01*
X482933Y-849089D01*
X483120Y-849172D01*
X483306Y-849130D01*
X483466Y-849005D01*
X483573Y-848839D01*
G01X484920Y-849172D02*
Y-847505D01*
G01Y-847839D02*
X485053Y-847672D01*
X485186Y-847547D01*
X485373Y-847505D01*
X485506Y-847547D01*
X485666Y-847672D01*
G01X487973Y-846672D02*
Y-849172D01*
G01Y-848797D02*
X487866Y-849005D01*
X487706Y-849130D01*
X487520Y-849172D01*
X487306Y-849089D01*
X487146Y-848880D01*
X487040Y-848630D01*
X487013Y-848339D01*
X487040Y-848047D01*
X487146Y-847797D01*
X487306Y-847589D01*
X487520Y-847505D01*
X487706Y-847547D01*
X487840Y-847630D01*
X487973Y-847797D01*
G01X491360Y-849172D02*
Y-846672D01*
X492026D01*
X492240Y-846797D01*
X492373Y-846964D01*
X492426Y-847297D01*
X492373Y-847630D01*
X492213Y-847839D01*
X492026Y-847964D01*
X491360D01*
G01X492026D02*
X492426Y-849172D01*
G01X493693Y-848047D02*
X494546D01*
X494466Y-847755D01*
X494333Y-847589D01*
X494146Y-847505D01*
X493960Y-847547D01*
X493800Y-847672D01*
X493693Y-847964D01*
X493640Y-848214D01*
Y-848464D01*
X493693Y-848714D01*
X493826Y-848964D01*
X493986Y-849130D01*
X494173Y-849172D01*
X494360Y-849089D01*
X494546Y-848839D01*
G01X495813Y-847505D02*
X496293Y-849172D01*
X496773Y-847505D01*
G01X498493Y-849255D02*
X498440Y-849214D01*
Y-849130D01*
X498493Y-849089D01*
X498546Y-849130D01*
Y-849214D01*
X498493Y-849255D01*
G01X500693Y-849172D02*
X500880Y-849130D01*
X501093Y-849005D01*
X501226Y-848797D01*
X501280Y-848505D01*
X501226Y-848214D01*
X501066Y-847964D01*
X500826Y-847839D01*
X500560D01*
X500400Y-847755D01*
X500266Y-847547D01*
X500213Y-847255D01*
X500293Y-846964D01*
X500480Y-846755D01*
X500693Y-846672D01*
X500906Y-846755D01*
X501093Y-846964D01*
X501173Y-847255D01*
X501120Y-847547D01*
X500986Y-847755D01*
X500826Y-847839D01*
X500560D01*
X500320Y-847964D01*
X500160Y-848214D01*
X500106Y-848505D01*
X500160Y-848797D01*
X500293Y-849005D01*
X500506Y-849130D01*
X500693Y-849172D01*
G01X503106Y-847839D02*
X503213Y-847714D01*
X503293Y-847505D01*
X503346Y-847214D01*
X503293Y-846964D01*
X503186Y-846797D01*
X503000Y-846672D01*
X502280D01*
Y-849172D01*
X503160D01*
X503346Y-849005D01*
X503453Y-848755D01*
X503506Y-848464D01*
X503453Y-848172D01*
X503293Y-847922D01*
X503106Y-847839D01*
X502280D01*
G01X465993Y-822172D02*
Y-827172D01*
G01X464536Y-822172D02*
X467450D01*
G01X471093Y-827172D02*
X470713Y-827089D01*
X470333Y-826755D01*
X470080Y-826172D01*
X469953Y-825505D01*
X470080Y-824839D01*
X470333Y-824255D01*
X470713Y-823922D01*
X471093Y-823839D01*
X471473Y-823922D01*
X471853Y-824255D01*
X472106Y-824839D01*
X472170Y-825505D01*
X472106Y-826172D01*
X471853Y-826755D01*
X471473Y-827089D01*
X471093Y-827172D01*
G01X476193D02*
X475813Y-827089D01*
X475433Y-826755D01*
X475180Y-826172D01*
X475053Y-825505D01*
X475180Y-824839D01*
X475433Y-824255D01*
X475813Y-823922D01*
X476193Y-823839D01*
X476573Y-823922D01*
X476953Y-824255D01*
X477206Y-824839D01*
X477270Y-825505D01*
X477206Y-826172D01*
X476953Y-826755D01*
X476573Y-827089D01*
X476193Y-827172D01*
G01X481293D02*
Y-822172D01*
G01X486393Y-827339D02*
X486266Y-827255D01*
Y-827089D01*
X486393Y-827005D01*
X486520Y-827089D01*
Y-827255D01*
X486393Y-827339D01*
G01Y-825089D02*
X486266Y-825005D01*
Y-824839D01*
X486393Y-824755D01*
X486520Y-824839D01*
Y-825005D01*
X486393Y-825089D01*
G01X462093Y-819672D02*
Y-844672D01*
G01Y-794672D02*
Y-819672D01*
G01X464726Y-802172D02*
Y-797172D01*
X466310D01*
X466816Y-797422D01*
X467133Y-797755D01*
X467260Y-798422D01*
X467133Y-799089D01*
X466753Y-799505D01*
X466310Y-799755D01*
X464726D01*
G01X466310D02*
X467260Y-802172D01*
G01X472360D02*
X469826D01*
Y-797172D01*
X472360D01*
G01X471346Y-799589D02*
X469826D01*
G01X474610Y-797172D02*
X476193Y-802172D01*
X477776Y-797172D01*
G01X481293Y-802339D02*
X481166Y-802255D01*
Y-802089D01*
X481293Y-802005D01*
X481420Y-802089D01*
Y-802255D01*
X481293Y-802339D01*
G01Y-800089D02*
X481166Y-800005D01*
Y-799839D01*
X481293Y-799755D01*
X481420Y-799839D01*
Y-800005D01*
X481293Y-800089D01*
G01X-297025Y-1013390D02*
Y1828909D01*
X3691357D01*
Y-1013390D01*
X-297025D01*
G01X16913Y-817022D02*
X18480D01*
Y-818912D01*
X18010Y-819542D01*
X17461Y-819962D01*
X16678Y-820172D01*
X15895Y-819962D01*
X15346Y-819542D01*
X14876Y-818912D01*
X14563Y-818177D01*
X14406Y-817337D01*
Y-816602D01*
X14563Y-815972D01*
X14876Y-815237D01*
X15346Y-814607D01*
X15816Y-814187D01*
X16443Y-813872D01*
X16991D01*
X17618Y-814082D01*
X18088Y-814502D01*
G01X21020Y-813872D02*
Y-818387D01*
X21333Y-819332D01*
X21960Y-819962D01*
X22743Y-820172D01*
X23526Y-819962D01*
X24153Y-819332D01*
X24466Y-818387D01*
Y-813872D01*
G01X28103D02*
X29983D01*
G01X29043D02*
Y-820172D01*
G01X28103D02*
X29983D01*
G01X33698Y-819332D02*
X34325Y-819857D01*
X35030Y-820172D01*
X35656D01*
X36283Y-819857D01*
X36753Y-819332D01*
X36988Y-818597D01*
X36831Y-817862D01*
X36440Y-817232D01*
X35735Y-816812D01*
X34795Y-816602D01*
X34246Y-816182D01*
X34011Y-815447D01*
X34168Y-814712D01*
X34560Y-814187D01*
X35108Y-813872D01*
X35656D01*
X36205Y-814082D01*
X36675Y-814607D01*
G01X39998Y-820172D02*
Y-813872D01*
G01X43288D02*
Y-820172D01*
G01Y-817022D02*
X39998D01*
G01X45985Y-820172D02*
X47943Y-813872D01*
X49901Y-820172D01*
G01X49196Y-817967D02*
X46690D01*
G01X52441Y-820172D02*
Y-813872D01*
X56045Y-820172D01*
Y-813872D01*
G01X65120Y-820172D02*
Y-813872D01*
X66686D01*
X67313Y-814187D01*
X67783Y-814607D01*
X68175Y-815237D01*
X68488Y-815972D01*
X68566Y-817022D01*
X68488Y-818072D01*
X68175Y-818807D01*
X67783Y-819437D01*
X67313Y-819857D01*
X66686Y-820172D01*
X65120D01*
G01X72203Y-813872D02*
X74083D01*
G01X73143D02*
Y-820172D01*
G01X72203D02*
X74083D01*
G01X77798Y-819332D02*
X78425Y-819857D01*
X79130Y-820172D01*
X79756D01*
X80383Y-819857D01*
X80853Y-819332D01*
X81088Y-818597D01*
X80931Y-817862D01*
X80540Y-817232D01*
X79835Y-816812D01*
X78895Y-816602D01*
X78346Y-816182D01*
X78111Y-815447D01*
X78268Y-814712D01*
X78660Y-814187D01*
X79208Y-813872D01*
X79756D01*
X80305Y-814082D01*
X80775Y-814607D01*
G01X85743Y-813872D02*
Y-820172D01*
G01X83941Y-813872D02*
X87545D01*
G01X92043Y-820382D02*
X91886Y-820277D01*
Y-820067D01*
X92043Y-819962D01*
X92200Y-820067D01*
Y-820277D01*
X92043Y-820382D01*
G01X98186Y-821327D02*
X98500Y-819962D01*
G01X104643Y-813872D02*
Y-820172D01*
G01X102841Y-813872D02*
X106445D01*
G01X108985Y-820172D02*
X110943Y-813872D01*
X112901Y-820172D01*
G01X112196Y-817967D02*
X109690D01*
G01X117243Y-820172D02*
X116616Y-820067D01*
X116068Y-819647D01*
X115598Y-819017D01*
X115285Y-818282D01*
X115128Y-817442D01*
Y-816602D01*
X115285Y-815762D01*
X115598Y-815027D01*
X116068Y-814397D01*
X116616Y-813977D01*
X117243Y-813872D01*
X117870Y-813977D01*
X118418Y-814397D01*
X118888Y-815027D01*
X119201Y-815762D01*
X119358Y-816602D01*
Y-817442D01*
X119201Y-818282D01*
X118888Y-819017D01*
X118418Y-819647D01*
X117870Y-820067D01*
X117243Y-820172D01*
G01X123543D02*
Y-817337D01*
X121976Y-813872D01*
G01X125110D02*
X123543Y-817337D01*
G01X128120Y-813872D02*
Y-818387D01*
X128433Y-819332D01*
X129060Y-819962D01*
X129843Y-820172D01*
X130626Y-819962D01*
X131253Y-819332D01*
X131566Y-818387D01*
Y-813872D01*
G01X134185Y-820172D02*
X136143Y-813872D01*
X138101Y-820172D01*
G01X137396Y-817967D02*
X134890D01*
G01X140641Y-820172D02*
Y-813872D01*
X144245Y-820172D01*
Y-813872D01*
G01X18166Y-824397D02*
X17696Y-824082D01*
X17148Y-823872D01*
X16521D01*
X15816Y-824187D01*
X15268Y-824712D01*
X14876Y-825342D01*
X14563Y-826392D01*
X14485Y-827337D01*
X14641Y-828282D01*
X14876Y-828912D01*
X15346Y-829542D01*
X15895Y-829962D01*
X16443Y-830172D01*
X16991D01*
X17540Y-829962D01*
X18010Y-829647D01*
X18401Y-829227D01*
G01X21803Y-823872D02*
X23683D01*
G01X22743D02*
Y-830172D01*
G01X21803D02*
X23683D01*
G01X29043Y-823872D02*
Y-830172D01*
G01X27241Y-823872D02*
X30845D01*
G01X35343Y-830172D02*
Y-827337D01*
X33776Y-823872D01*
G01X36910D02*
X35343Y-827337D01*
G01X46220Y-828912D02*
X46690Y-829647D01*
X47316Y-830067D01*
X48021Y-830172D01*
X48648Y-830067D01*
X49275Y-829542D01*
X49666Y-828912D01*
X49745Y-828282D01*
X49588Y-827547D01*
X49040Y-827022D01*
X48491Y-826812D01*
X47786D01*
G01X48491D02*
X48961Y-826497D01*
X49353Y-825972D01*
X49510Y-825342D01*
X49353Y-824712D01*
X48961Y-824187D01*
X48256Y-823872D01*
X47551Y-823977D01*
X46846Y-824397D01*
G01X52520Y-828912D02*
X52990Y-829647D01*
X53616Y-830067D01*
X54321Y-830172D01*
X54948Y-830067D01*
X55575Y-829542D01*
X55966Y-828912D01*
X56045Y-828282D01*
X55888Y-827547D01*
X55340Y-827022D01*
X54791Y-826812D01*
X54086D01*
G01X54791D02*
X55261Y-826497D01*
X55653Y-825972D01*
X55810Y-825342D01*
X55653Y-824712D01*
X55261Y-824187D01*
X54556Y-823872D01*
X53851Y-823977D01*
X53146Y-824397D01*
G01X58820Y-828912D02*
X59290Y-829647D01*
X59916Y-830067D01*
X60621Y-830172D01*
X61248Y-830067D01*
X61875Y-829542D01*
X62266Y-828912D01*
X62345Y-828282D01*
X62188Y-827547D01*
X61640Y-827022D01*
X61091Y-826812D01*
X60386D01*
G01X61091D02*
X61561Y-826497D01*
X61953Y-825972D01*
X62110Y-825342D01*
X61953Y-824712D01*
X61561Y-824187D01*
X60856Y-823872D01*
X60151Y-823977D01*
X59446Y-824397D01*
G01X66686Y-830172D02*
X66843Y-828807D01*
X67078Y-827652D01*
X67391Y-826602D01*
X67783Y-825447D01*
X68410Y-823872D01*
X65276D01*
G01X72986Y-830172D02*
X73143Y-828807D01*
X73378Y-827652D01*
X73691Y-826602D01*
X74083Y-825447D01*
X74710Y-823872D01*
X71576D01*
G01X79286Y-831327D02*
X79600Y-829962D01*
G01X85743Y-823872D02*
Y-830172D01*
G01X83941Y-823872D02*
X87545D01*
G01X90085Y-830172D02*
X92043Y-823872D01*
X94001Y-830172D01*
G01X93296Y-827967D02*
X90790D01*
G01X97403Y-823872D02*
X99283D01*
G01X98343D02*
Y-830172D01*
G01X97403D02*
X99283D01*
G01X102293Y-823872D02*
X103390Y-830172D01*
X104643Y-823872D01*
X105896Y-830172D01*
X106993Y-823872D01*
G01X108985Y-830172D02*
X110943Y-823872D01*
X112901Y-830172D01*
G01X112196Y-827967D02*
X109690D01*
G01X115441Y-830172D02*
Y-823872D01*
X119045Y-830172D01*
Y-823872D01*
G01X129451Y-832272D02*
X128668Y-831222D01*
X128276Y-830172D01*
Y-825972D01*
X128668Y-824922D01*
X129451Y-823872D01*
G01X140876Y-830172D02*
Y-823872D01*
X142835D01*
X143461Y-824187D01*
X143853Y-824607D01*
X144010Y-825447D01*
X143853Y-826287D01*
X143383Y-826812D01*
X142835Y-827127D01*
X140876D01*
G01X142835D02*
X144010Y-830172D01*
G01X148743Y-830382D02*
X148586Y-830277D01*
Y-830067D01*
X148743Y-829962D01*
X148900Y-830067D01*
Y-830277D01*
X148743Y-830382D01*
G01X155043Y-830172D02*
X154416Y-830067D01*
X153868Y-829647D01*
X153398Y-829017D01*
X153085Y-828282D01*
X152928Y-827442D01*
Y-826602D01*
X153085Y-825762D01*
X153398Y-825027D01*
X153868Y-824397D01*
X154416Y-823977D01*
X155043Y-823872D01*
X155670Y-823977D01*
X156218Y-824397D01*
X156688Y-825027D01*
X157001Y-825762D01*
X157158Y-826602D01*
Y-827442D01*
X157001Y-828282D01*
X156688Y-829017D01*
X156218Y-829647D01*
X155670Y-830067D01*
X155043Y-830172D01*
G01X161343Y-830382D02*
X161186Y-830277D01*
Y-830067D01*
X161343Y-829962D01*
X161500Y-830067D01*
Y-830277D01*
X161343Y-830382D01*
G01X169366Y-824397D02*
X168896Y-824082D01*
X168348Y-823872D01*
X167721D01*
X167016Y-824187D01*
X166468Y-824712D01*
X166076Y-825342D01*
X165763Y-826392D01*
X165685Y-827337D01*
X165841Y-828282D01*
X166076Y-828912D01*
X166546Y-829542D01*
X167095Y-829962D01*
X167643Y-830172D01*
X168191D01*
X168740Y-829962D01*
X169210Y-829647D01*
X169601Y-829227D01*
G01X173943Y-830382D02*
X173786Y-830277D01*
Y-830067D01*
X173943Y-829962D01*
X174100Y-830067D01*
Y-830277D01*
X173943Y-830382D01*
G01X180635Y-832272D02*
X181418Y-831222D01*
X181810Y-830172D01*
Y-825972D01*
X181418Y-824922D01*
X180635Y-823872D01*
G01X38743Y-799472D02*
X36223Y-799055D01*
X34018Y-797389D01*
X32128Y-794889D01*
X30868Y-791972D01*
X30238Y-788639D01*
Y-785305D01*
X30868Y-781972D01*
X32128Y-779055D01*
X34018Y-776556D01*
X36223Y-774889D01*
X38743Y-774472D01*
X41263Y-774889D01*
X43468Y-776556D01*
X45358Y-779055D01*
X46618Y-781972D01*
X47248Y-785305D01*
Y-788639D01*
X46618Y-791972D01*
X45358Y-794889D01*
X43468Y-797389D01*
X41263Y-799055D01*
X38743Y-799472D01*
G01X41263Y-792805D02*
X45043Y-799472D01*
G01X58588Y-782806D02*
Y-794472D01*
X59848Y-797389D01*
X61738Y-799055D01*
X63943Y-799472D01*
X66148Y-799055D01*
X68038Y-797389D01*
X69298Y-794472D01*
G01Y-799472D02*
Y-782806D01*
G01X94813Y-799472D02*
Y-782806D01*
G01Y-785722D02*
X93553Y-784056D01*
X91663Y-783222D01*
X89458Y-782806D01*
X87253Y-783639D01*
X85363Y-785305D01*
X84103Y-787806D01*
X83473Y-791139D01*
X84103Y-794472D01*
X85363Y-796973D01*
X87253Y-798639D01*
X89458Y-799472D01*
X91663Y-799055D01*
X93553Y-797806D01*
X94813Y-796139D01*
G01X108988Y-799472D02*
Y-782806D01*
G01Y-786972D02*
X110248Y-784889D01*
X112138Y-783222D01*
X114658Y-782806D01*
X116863Y-783222D01*
X118753Y-784889D01*
X119698Y-787806D01*
Y-799472D01*
G01X139543Y-774472D02*
Y-799472D01*
G01X135133Y-782806D02*
X143953D01*
G01X170413Y-799472D02*
Y-782806D01*
G01Y-785722D02*
X169153Y-784056D01*
X167263Y-783222D01*
X165058Y-782806D01*
X162853Y-783639D01*
X160963Y-785305D01*
X159703Y-787806D01*
X159073Y-791139D01*
X159703Y-794472D01*
X160963Y-796973D01*
X162853Y-798639D01*
X165058Y-799472D01*
X167263Y-799055D01*
X169153Y-797806D01*
X170413Y-796139D01*
G01X14641Y-810172D02*
Y-803872D01*
X18245Y-810172D01*
Y-803872D01*
G01X22743Y-810172D02*
X22116Y-810067D01*
X21568Y-809647D01*
X21098Y-809017D01*
X20785Y-808282D01*
X20628Y-807442D01*
Y-806602D01*
X20785Y-805762D01*
X21098Y-805027D01*
X21568Y-804397D01*
X22116Y-803977D01*
X22743Y-803872D01*
X23370Y-803977D01*
X23918Y-804397D01*
X24388Y-805027D01*
X24701Y-805762D01*
X24858Y-806602D01*
Y-807442D01*
X24701Y-808282D01*
X24388Y-809017D01*
X23918Y-809647D01*
X23370Y-810067D01*
X22743Y-810172D01*
G01X29043Y-810382D02*
X28886Y-810277D01*
Y-810067D01*
X29043Y-809962D01*
X29200Y-810067D01*
Y-810277D01*
X29043Y-810382D01*
G01X33855Y-804922D02*
X34325Y-804292D01*
X34873Y-803977D01*
X35500Y-803872D01*
X36283Y-804082D01*
X36831Y-804607D01*
X36988Y-805237D01*
X36910Y-805867D01*
X36596Y-806392D01*
X35030Y-807442D01*
X34325Y-808177D01*
X33855Y-809227D01*
X33698Y-810172D01*
X36988D01*
G01X41643D02*
Y-803872D01*
X40703Y-805132D01*
G01Y-810172D02*
X42583D01*
G01X47943D02*
Y-803872D01*
X47003Y-805132D01*
G01Y-810172D02*
X48883D01*
G01X54086Y-811327D02*
X54400Y-809962D01*
G01X58193Y-803872D02*
X59290Y-810172D01*
X60543Y-803872D01*
X61796Y-810172D01*
X62893Y-803872D01*
G01X68410Y-810172D02*
X65276D01*
Y-803872D01*
X68410D01*
G01X67156Y-806917D02*
X65276D01*
G01X71341Y-810172D02*
Y-803872D01*
X74945Y-810172D01*
Y-803872D01*
G01X77798Y-810172D02*
Y-803872D01*
G01X81088D02*
Y-810172D01*
G01Y-807022D02*
X77798D01*
G01X84020Y-803872D02*
Y-808387D01*
X84333Y-809332D01*
X84960Y-809962D01*
X85743Y-810172D01*
X86526Y-809962D01*
X87153Y-809332D01*
X87466Y-808387D01*
Y-803872D01*
G01X90085Y-810172D02*
X92043Y-803872D01*
X94001Y-810172D01*
G01X93296Y-807967D02*
X90790D01*
G01X103155Y-804922D02*
X103625Y-804292D01*
X104173Y-803977D01*
X104800Y-803872D01*
X105583Y-804082D01*
X106131Y-804607D01*
X106288Y-805237D01*
X106210Y-805867D01*
X105896Y-806392D01*
X104330Y-807442D01*
X103625Y-808177D01*
X103155Y-809227D01*
X102998Y-810172D01*
X106288D01*
G01X109141D02*
Y-803872D01*
X112745Y-810172D01*
Y-803872D01*
G01X115520Y-810172D02*
Y-803872D01*
X117086D01*
X117713Y-804187D01*
X118183Y-804607D01*
X118575Y-805237D01*
X118888Y-805972D01*
X118966Y-807022D01*
X118888Y-808072D01*
X118575Y-808807D01*
X118183Y-809437D01*
X117713Y-809857D01*
X117086Y-810172D01*
X115520D01*
G01X128276D02*
Y-803872D01*
X130235D01*
X130861Y-804187D01*
X131253Y-804607D01*
X131410Y-805447D01*
X131253Y-806287D01*
X130783Y-806812D01*
X130235Y-807127D01*
X128276D01*
G01X130235D02*
X131410Y-810172D01*
G01X134420D02*
Y-803872D01*
X135986D01*
X136613Y-804187D01*
X137083Y-804607D01*
X137475Y-805237D01*
X137788Y-805972D01*
X137866Y-807022D01*
X137788Y-808072D01*
X137475Y-808807D01*
X137083Y-809437D01*
X136613Y-809857D01*
X135986Y-810172D01*
X134420D01*
G01X142443Y-810382D02*
X142286Y-810277D01*
Y-810067D01*
X142443Y-809962D01*
X142600Y-810067D01*
Y-810277D01*
X142443Y-810382D01*
G01X210093Y-779172D02*
Y-787172D01*
X214093D01*
G01X221893D02*
Y-781839D01*
G01Y-782772D02*
X221493Y-782239D01*
X220893Y-781972D01*
X220193Y-781839D01*
X219493Y-782105D01*
X218893Y-782639D01*
X218493Y-783439D01*
X218293Y-784505D01*
X218493Y-785572D01*
X218893Y-786372D01*
X219493Y-786905D01*
X220193Y-787172D01*
X220893Y-787039D01*
X221493Y-786639D01*
X221893Y-786106D01*
G01X225993Y-789572D02*
X226593Y-789839D01*
X227393Y-789572D01*
X227893Y-789039D01*
X228293Y-788372D01*
X228893Y-786239D01*
X230193Y-781839D01*
G01X226993D02*
X228893Y-786239D01*
G01X234593Y-783572D02*
X237793D01*
X237493Y-782639D01*
X236993Y-782105D01*
X236293Y-781839D01*
X235593Y-781972D01*
X234993Y-782372D01*
X234593Y-783305D01*
X234393Y-784106D01*
Y-784905D01*
X234593Y-785705D01*
X235093Y-786505D01*
X235693Y-787039D01*
X236393Y-787172D01*
X237093Y-786905D01*
X237793Y-786106D01*
G01X242693Y-787172D02*
Y-781839D01*
G01Y-782905D02*
X243193Y-782372D01*
X243693Y-781972D01*
X244393Y-781839D01*
X244893Y-781972D01*
X245493Y-782372D01*
G01X229193Y-829172D02*
X232993D01*
X229193Y-837172D01*
X232993D01*
G01X239093Y-831839D02*
Y-837172D01*
G01Y-829705D02*
X238893Y-829572D01*
Y-829305D01*
X239093Y-829172D01*
X239293Y-829305D01*
Y-829572D01*
X239093Y-829705D01*
G01X245793Y-834505D02*
X248393D01*
G01X253093Y-837172D02*
Y-829172D01*
X255493D01*
X256293Y-829572D01*
X256893Y-830505D01*
X257093Y-831572D01*
X256893Y-832639D01*
X256393Y-833439D01*
X255493Y-833839D01*
X253093D01*
G01X263093Y-831839D02*
Y-837172D01*
G01Y-829705D02*
X262893Y-829572D01*
Y-829305D01*
X263093Y-829172D01*
X263293Y-829305D01*
Y-829572D01*
X263093Y-829705D01*
G01X269393Y-837172D02*
Y-831839D01*
G01Y-833172D02*
X269793Y-832505D01*
X270393Y-831972D01*
X271193Y-831839D01*
X271893Y-831972D01*
X272493Y-832505D01*
X272793Y-833439D01*
Y-837172D01*
G01X277693Y-839172D02*
X278393Y-839705D01*
X279193Y-839839D01*
X279893Y-839705D01*
X280493Y-839039D01*
X280893Y-838105D01*
Y-831839D01*
G01Y-832905D02*
X280493Y-832372D01*
X279893Y-831972D01*
X279193Y-831839D01*
X278393Y-832105D01*
X277893Y-832639D01*
X277493Y-833572D01*
X277293Y-834505D01*
X277393Y-835305D01*
X277793Y-836239D01*
X278393Y-836905D01*
X279193Y-837172D01*
X279793Y-837039D01*
X280493Y-836505D01*
X280893Y-835972D01*
G01X238593Y-804172D02*
X241093Y-812172D01*
X243593Y-804172D01*
G01X251293Y-804839D02*
X250693Y-804439D01*
X249993Y-804172D01*
X249193D01*
X248293Y-804572D01*
X247593Y-805239D01*
X247093Y-806039D01*
X246693Y-807372D01*
X246593Y-808572D01*
X246793Y-809772D01*
X247093Y-810572D01*
X247693Y-811372D01*
X248393Y-811905D01*
X249093Y-812172D01*
X249793D01*
X250493Y-811905D01*
X251093Y-811505D01*
X251593Y-810972D01*
G01X259293Y-804839D02*
X258693Y-804439D01*
X257993Y-804172D01*
X257193D01*
X256293Y-804572D01*
X255593Y-805239D01*
X255093Y-806039D01*
X254693Y-807372D01*
X254593Y-808572D01*
X254793Y-809772D01*
X255093Y-810572D01*
X255693Y-811372D01*
X256393Y-811905D01*
X257093Y-812172D01*
X257793D01*
X258493Y-811905D01*
X259093Y-811505D01*
X259593Y-810972D01*
G01X261393Y-785972D02*
X261993Y-786639D01*
X262693Y-787039D01*
X263593Y-787172D01*
X264493Y-786905D01*
X265193Y-786372D01*
X265693Y-785439D01*
X265793Y-784372D01*
X265593Y-783305D01*
X265093Y-782639D01*
X264393Y-782105D01*
X263693Y-781972D01*
X262993Y-782105D01*
X262093Y-782639D01*
X262393Y-779172D01*
X265093D01*
G01X336693Y-830505D02*
X337293Y-829705D01*
X337993Y-829305D01*
X338793Y-829172D01*
X339793Y-829439D01*
X340493Y-830105D01*
X340693Y-830905D01*
X340593Y-831706D01*
X340193Y-832372D01*
X338193Y-833705D01*
X337293Y-834639D01*
X336693Y-835972D01*
X336493Y-837172D01*
X340693D01*
G01X346593Y-829172D02*
X345793Y-829439D01*
X345193Y-830105D01*
X344793Y-830905D01*
X344493Y-831972D01*
X344393Y-833172D01*
X344493Y-834372D01*
X344793Y-835439D01*
X345193Y-836239D01*
X345793Y-836905D01*
X346593Y-837172D01*
X347393Y-836905D01*
X347993Y-836239D01*
X348393Y-835439D01*
X348693Y-834372D01*
X348793Y-833172D01*
X348693Y-831972D01*
X348393Y-830905D01*
X347993Y-830105D01*
X347393Y-829439D01*
X346593Y-829172D01*
G01X352693Y-830505D02*
X353293Y-829705D01*
X353993Y-829305D01*
X354793Y-829172D01*
X355793Y-829439D01*
X356493Y-830105D01*
X356693Y-830905D01*
X356593Y-831706D01*
X356193Y-832372D01*
X354193Y-833705D01*
X353293Y-834639D01*
X352693Y-835972D01*
X352493Y-837172D01*
X356693D01*
G01X360693Y-830505D02*
X361293Y-829705D01*
X361993Y-829305D01*
X362793Y-829172D01*
X363793Y-829439D01*
X364493Y-830105D01*
X364693Y-830905D01*
X364593Y-831706D01*
X364193Y-832372D01*
X362193Y-833705D01*
X361293Y-834639D01*
X360693Y-835972D01*
X360493Y-837172D01*
X364693D01*
G01X368793Y-837439D02*
X372393Y-829172D01*
G01X378593Y-837172D02*
Y-829172D01*
X377393Y-830772D01*
G01Y-837172D02*
X379793D01*
G01X384693Y-830505D02*
X385293Y-829705D01*
X385993Y-829305D01*
X386793Y-829172D01*
X387793Y-829439D01*
X388493Y-830105D01*
X388693Y-830905D01*
X388593Y-831706D01*
X388193Y-832372D01*
X386193Y-833705D01*
X385293Y-834639D01*
X384693Y-835972D01*
X384493Y-837172D01*
X388693D01*
G01X392793Y-837439D02*
X396393Y-829172D01*
G01X402593D02*
X401793Y-829439D01*
X401193Y-830105D01*
X400793Y-830905D01*
X400493Y-831972D01*
X400393Y-833172D01*
X400493Y-834372D01*
X400793Y-835439D01*
X401193Y-836239D01*
X401793Y-836905D01*
X402593Y-837172D01*
X403393Y-836905D01*
X403993Y-836239D01*
X404393Y-835439D01*
X404693Y-834372D01*
X404793Y-833172D01*
X404693Y-831972D01*
X404393Y-830905D01*
X403993Y-830105D01*
X403393Y-829439D01*
X402593Y-829172D01*
G01X408693Y-830505D02*
X409293Y-829705D01*
X409993Y-829305D01*
X410793Y-829172D01*
X411793Y-829439D01*
X412493Y-830105D01*
X412693Y-830905D01*
X412593Y-831706D01*
X412193Y-832372D01*
X410193Y-833705D01*
X409293Y-834639D01*
X408693Y-835972D01*
X408493Y-837172D01*
X412693D01*
G01X336393Y-814672D02*
Y-806672D01*
X338393D01*
X339193Y-807072D01*
X339793Y-807605D01*
X340293Y-808405D01*
X340693Y-809339D01*
X340793Y-810672D01*
X340693Y-812005D01*
X340293Y-812939D01*
X339793Y-813739D01*
X339193Y-814272D01*
X338393Y-814672D01*
X336393D01*
G01X344093D02*
X346593Y-806672D01*
X349093Y-814672D01*
G01X348193Y-811872D02*
X344993D01*
G01X354593Y-806672D02*
X353793Y-806939D01*
X353193Y-807605D01*
X352793Y-808405D01*
X352493Y-809472D01*
X352393Y-810672D01*
X352493Y-811872D01*
X352793Y-812939D01*
X353193Y-813739D01*
X353793Y-814405D01*
X354593Y-814672D01*
X355393Y-814405D01*
X355993Y-813739D01*
X356393Y-812939D01*
X356693Y-811872D01*
X356793Y-810672D01*
X356693Y-809472D01*
X356393Y-808405D01*
X355993Y-807605D01*
X355393Y-806939D01*
X354593Y-806672D01*
G01X360693Y-814672D02*
Y-806672D01*
X364493D01*
G01X363093Y-810539D02*
X360693D01*
G01X370593Y-806672D02*
X369793Y-806939D01*
X369193Y-807605D01*
X368793Y-808405D01*
X368493Y-809472D01*
X368393Y-810672D01*
X368493Y-811872D01*
X368793Y-812939D01*
X369193Y-813739D01*
X369793Y-814405D01*
X370593Y-814672D01*
X371393Y-814405D01*
X371993Y-813739D01*
X372393Y-812939D01*
X372693Y-811872D01*
X372793Y-810672D01*
X372693Y-809472D01*
X372393Y-808405D01*
X371993Y-807605D01*
X371393Y-806939D01*
X370593Y-806672D01*
G01X378593D02*
Y-814672D01*
G01X376293Y-806672D02*
X380893D01*
G01X384593Y-814672D02*
Y-806672D01*
X386993D01*
X387793Y-807072D01*
X388393Y-808005D01*
X388593Y-809072D01*
X388393Y-810139D01*
X387893Y-810939D01*
X386993Y-811339D01*
X384593D01*
G01X395393Y-810405D02*
X395793Y-810005D01*
X396093Y-809339D01*
X396293Y-808405D01*
X396093Y-807605D01*
X395693Y-807072D01*
X394993Y-806672D01*
X392293D01*
Y-814672D01*
X395593D01*
X396293Y-814139D01*
X396693Y-813339D01*
X396893Y-812405D01*
X396693Y-811472D01*
X396093Y-810672D01*
X395393Y-810405D01*
X392293D01*
G01X400093Y-814672D02*
X402593Y-806672D01*
X405093Y-814672D01*
G01X404193Y-811872D02*
X400993D01*
G01X408693Y-814672D02*
Y-806672D01*
X412493D01*
G01X411093Y-810539D02*
X408693D01*
G01X418593Y-806672D02*
X417793Y-806939D01*
X417193Y-807605D01*
X416793Y-808405D01*
X416493Y-809472D01*
X416393Y-810672D01*
X416493Y-811872D01*
X416793Y-812939D01*
X417193Y-813739D01*
X417793Y-814405D01*
X418593Y-814672D01*
X419393Y-814405D01*
X419993Y-813739D01*
X420393Y-812939D01*
X420693Y-811872D01*
X420793Y-810672D01*
X420693Y-809472D01*
X420393Y-808405D01*
X419993Y-807605D01*
X419393Y-806939D01*
X418593Y-806672D01*
G01X356693Y-787172D02*
Y-779172D01*
X360493D01*
G01X359093Y-783039D02*
X356693D01*
G01X366593Y-779172D02*
X365793Y-779439D01*
X365193Y-780105D01*
X364793Y-780905D01*
X364493Y-781972D01*
X364393Y-783172D01*
X364493Y-784372D01*
X364793Y-785439D01*
X365193Y-786239D01*
X365793Y-786905D01*
X366593Y-787172D01*
X367393Y-786905D01*
X367993Y-786239D01*
X368393Y-785439D01*
X368693Y-784372D01*
X368793Y-783172D01*
X368693Y-781972D01*
X368393Y-780905D01*
X367993Y-780105D01*
X367393Y-779439D01*
X366593Y-779172D01*
G01X374593D02*
Y-787172D01*
G01X372293Y-779172D02*
X376893D01*
G01X379593Y-789839D02*
X385593D01*
G01X388593Y-787172D02*
Y-779172D01*
X390993D01*
X391793Y-779572D01*
X392393Y-780505D01*
X392593Y-781572D01*
X392393Y-782639D01*
X391893Y-783439D01*
X390993Y-783839D01*
X388593D01*
G01X396393Y-787172D02*
Y-779172D01*
X398393D01*
X399193Y-779572D01*
X399793Y-780105D01*
X400293Y-780905D01*
X400693Y-781839D01*
X400793Y-783172D01*
X400693Y-784505D01*
X400293Y-785439D01*
X399793Y-786239D01*
X399193Y-786772D01*
X398393Y-787172D01*
X396393D01*
G01X407393Y-782905D02*
X407793Y-782505D01*
X408093Y-781839D01*
X408293Y-780905D01*
X408093Y-780105D01*
X407693Y-779572D01*
X406993Y-779172D01*
X404293D01*
Y-787172D01*
X407593D01*
X408293Y-786639D01*
X408693Y-785839D01*
X408893Y-784905D01*
X408693Y-783972D01*
X408093Y-783172D01*
X407393Y-782905D01*
X404293D01*
G01X411593Y-789839D02*
X417593D01*
G01X424793Y-779839D02*
X424193Y-779439D01*
X423493Y-779172D01*
X422693D01*
X421793Y-779572D01*
X421093Y-780239D01*
X420593Y-781039D01*
X420193Y-782372D01*
X420093Y-783572D01*
X420293Y-784772D01*
X420593Y-785572D01*
X421193Y-786372D01*
X421893Y-786905D01*
X422593Y-787172D01*
X423293D01*
X423993Y-786905D01*
X424593Y-786505D01*
X425093Y-785972D01*
G01X430593Y-787172D02*
X429793Y-787039D01*
X429093Y-786505D01*
X428493Y-785705D01*
X428093Y-784772D01*
X427893Y-783705D01*
Y-782639D01*
X428093Y-781572D01*
X428493Y-780639D01*
X429093Y-779839D01*
X429793Y-779305D01*
X430593Y-779172D01*
X431393Y-779305D01*
X432093Y-779839D01*
X432693Y-780639D01*
X433093Y-781572D01*
X433293Y-782639D01*
Y-783705D01*
X433093Y-784772D01*
X432693Y-785705D01*
X432093Y-786505D01*
X431393Y-787039D01*
X430593Y-787172D01*
G01X436293D02*
Y-779172D01*
X440893Y-787172D01*
Y-779172D01*
G01X444093D02*
X446593Y-787172D01*
X449093Y-779172D01*
G01X456593Y-787172D02*
X452593D01*
Y-779172D01*
X456593D01*
G01X454993Y-783039D02*
X452593D01*
G01X460593Y-787172D02*
Y-779172D01*
X463093D01*
X463893Y-779572D01*
X464393Y-780105D01*
X464593Y-781172D01*
X464393Y-782239D01*
X463793Y-782905D01*
X463093Y-783305D01*
X460593D01*
G01X463093D02*
X464593Y-787172D01*
G01X470593Y-779172D02*
Y-787172D01*
G01X468293Y-779172D02*
X472893D01*
G01X480593Y-787172D02*
X476593D01*
Y-779172D01*
X480593D01*
G01X478993Y-783039D02*
X476593D01*
G01X484593Y-787172D02*
Y-779172D01*
X487093D01*
X487893Y-779572D01*
X488393Y-780105D01*
X488593Y-781172D01*
X488393Y-782239D01*
X487793Y-782905D01*
X487093Y-783305D01*
X484593D01*
G01X487093D02*
X488593Y-787172D01*
G01X425093Y-840172D02*
Y-832172D01*
X423893Y-833772D01*
G01Y-840172D02*
X426293D01*
G01X431193Y-836839D02*
X431893Y-835905D01*
X432493Y-835372D01*
X433293Y-835105D01*
X433993Y-835372D01*
X434493Y-835905D01*
X434893Y-836705D01*
X434993Y-837639D01*
X434893Y-838439D01*
X434493Y-839239D01*
X433893Y-839905D01*
X433193Y-840172D01*
X432393Y-839905D01*
X431693Y-839106D01*
X431293Y-837905D01*
X431193Y-836572D01*
X431393Y-834839D01*
X431693Y-833905D01*
X432193Y-832972D01*
X432893Y-832305D01*
X433593Y-832172D01*
X434293Y-832439D01*
X434793Y-833105D01*
G01X441093Y-840439D02*
X440893Y-840305D01*
Y-840039D01*
X441093Y-839905D01*
X441293Y-840039D01*
Y-840305D01*
X441093Y-840439D01*
G01X447193Y-836839D02*
X447893Y-835905D01*
X448493Y-835372D01*
X449293Y-835105D01*
X449993Y-835372D01*
X450493Y-835905D01*
X450893Y-836705D01*
X450993Y-837639D01*
X450893Y-838439D01*
X450493Y-839239D01*
X449893Y-839905D01*
X449193Y-840172D01*
X448393Y-839905D01*
X447693Y-839106D01*
X447293Y-837905D01*
X447193Y-836572D01*
X447393Y-834839D01*
X447693Y-833905D01*
X448193Y-832972D01*
X448893Y-832305D01*
X449593Y-832172D01*
X450293Y-832439D01*
X450793Y-833105D01*
G01X470093Y-840172D02*
Y-832172D01*
X468893Y-833772D01*
G01Y-840172D02*
X471293D01*
G01X477893D02*
X478093Y-838439D01*
X478393Y-836972D01*
X478793Y-835639D01*
X479293Y-834172D01*
X480093Y-832172D01*
X476093D01*
G01X486093Y-840439D02*
X485893Y-840305D01*
Y-840039D01*
X486093Y-839905D01*
X486293Y-840039D01*
Y-840305D01*
X486093Y-840439D01*
G01X492193Y-833505D02*
X492793Y-832705D01*
X493493Y-832305D01*
X494293Y-832172D01*
X495293Y-832439D01*
X495993Y-833105D01*
X496193Y-833905D01*
X496093Y-834706D01*
X495693Y-835372D01*
X493693Y-836705D01*
X492793Y-837639D01*
X492193Y-838972D01*
X491993Y-840172D01*
X496193D01*
G01X490193Y-815172D02*
Y-807172D01*
X493993D01*
G01X492593Y-811039D02*
X490193D01*
G54D38*
G01X742000Y341500D02*
Y343500D01*
X702200Y356000D03*
X803500Y259525D03*
X850500Y356925D03*
G54D49*
G01X703896Y352170D02*
X702200Y353866D01*
G01D02*
Y356000D01*
G01X800890Y264375D02*
X803500Y261765D01*
Y259525D01*
G01X800575Y338000D02*
X803251D01*
G01X831000Y270500D02*
Y272879D01*
G01X808500Y276075D02*
Y279416D01*
G01X830000Y356581D02*
X829500Y356081D01*
Y354925D01*
G01X841000Y270500D02*
Y272462D01*
G01X846000Y270525D02*
Y273139D01*
G01X851000Y270525D02*
Y273525D01*
G01X836000Y270500D02*
Y272582D01*
G01X855318Y274234D02*
X856000Y273552D01*
Y270525D01*
G01X850500Y356925D02*
Y352651D01*
M02*
